FILE_TYPE = MACRO_DRAWING;
SET COLOR_WIRE YELLOW;
SET COLOR_PROP ORANGE;
SET COLOR_DOT WHITE;
SET COLOR_ARC YELLOW;
SET COLOR_BODY GREEN;
SET COLOR_NOTE PURPLE;
SET PROP_DISPLAY VALUE;
SET PAGE_NUMBER P181;
FORCEADD Q_CAP..1
(-11900 2250);
FORCEPROP 1 LAST LOCATION PC176_10
J 0
(-11850 2350);
DISPLAY 0.489362 (-11850 2350);
PAINT SKYBLUE (-11850 2350);
FORCEPROP 0 LAST $SEC 1
J 0
(-11850 2375);
DISPLAY 0.680851 (-11850 2375);
PAINT MONO (-11850 2375);
DISPLAY INVISIBLE (-11850 2375);
FORCEPROP 2 LAST CDS_SEC 1
J 0
(-11900 2500);
DISPLAY 1.021277 (-11900 2500);
DISPLAY INVISIBLE (-11900 2500);
FORCEPROP 1 LASTPIN (-11900 2350) $PN 1
J 0
(-11890 2330);
DISPLAY 0.489362 (-11890 2330);
PAINT MONO (-11890 2330);
FORCEPROP 1 LASTPIN (-11900 2150) $PN 2
J 0
(-11890 2130);
DISPLAY 0.489362 (-11890 2130);
PAINT MONO (-11890 2130);
FORCEPROP 1 LAST VALUE 0.1UF
J 0
(-11850 2300);
DISPLAY 0.489362 (-11850 2300);
PAINT SKYBLUE (-11850 2300);
FORCEPROP 1 LAST PACK_TYPE 0402
J 0
(-11850 2050);
DISPLAY 0.489362 (-11850 2050);
PAINT SKYBLUE (-11850 2050);
FORCEPROP 1 LAST VOLTAGE 25V
J 0
(-11850 2250);
DISPLAY 0.489362 (-11850 2250);
PAINT SKYBLUE (-11850 2250);
FORCEPROP 1 LAST TOLERANCE 10%
J 0
(-11850 2200);
DISPLAY 0.489362 (-11850 2200);
PAINT SKYBLUE (-11850 2200);
FORCEPROP 1 LAST MATERIAL X7R
J 0
(-11850 2150);
DISPLAY 0.489362 (-11850 2150);
PAINT SKYBLUE (-11850 2150);
FORCEPROP 2 LAST CDS_LIB pure_quanta
J 0
(-11900 2250);
PAINT MONO (-11900 2250);
DISPLAY INVISIBLE (-11900 2250);
FORCEPROP 1 LAST PATH I1
J 0
(-11850 2400);
DISPLAY 0.978723 (-11850 2400);
PAINT WHITE (-11850 2400);
DISPLAY INVISIBLE (-11850 2400);
FORCEPROP 1 LAST PART_NUMBER CH4104K1B00
J 0
(-11850 2100);
DISPLAY 0.489362 (-11850 2100);
PAINT SKYBLUE (-11850 2100);
DISPLAY INVISIBLE (-11850 2100);
FORCEADD Q_CAP..1
(-11050 3025);
FORCEPROP 1 LAST LOCATION PC171
J 0
(-11000 3125);
DISPLAY 0.489362 (-11000 3125);
PAINT SKYBLUE (-11000 3125);
FORCEPROP 0 LAST $SEC 1
J 0
(-11000 3175);
DISPLAY 0.680851 (-11000 3175);
PAINT MONO (-11000 3175);
DISPLAY INVISIBLE (-11000 3175);
FORCEPROP 0 LAST CDS_SEC 1
J 0
(-11000 3175);
DISPLAY 1.021277 (-11000 3175);
DISPLAY INVISIBLE (-11000 3175);
FORCEPROP 1 LASTPIN (-11050 3125) $PN 1
J 0
(-11040 3105);
DISPLAY 0.489362 (-11040 3105);
PAINT MONO (-11040 3105);
FORCEPROP 1 LASTPIN (-11050 2925) $PN 2
J 0
(-11040 2905);
DISPLAY 0.489362 (-11040 2905);
PAINT MONO (-11040 2905);
FORCEPROP 1 LAST PACK_TYPE C0402
J 0
(-11000 2825);
DISPLAY 0.489362 (-11000 2825);
PAINT SKYBLUE (-11000 2825);
FORCEPROP 1 LAST VOLTAGE 10V
J 0
(-11000 3025);
DISPLAY 0.489362 (-11000 3025);
PAINT SKYBLUE (-11000 3025);
FORCEPROP 1 LAST VALUE 2.2UF
J 0
(-11000 3075);
DISPLAY 0.489362 (-11000 3075);
PAINT SKYBLUE (-11000 3075);
FORCEPROP 1 LAST TOLERANCE 10%
J 0
(-11000 2975);
DISPLAY 0.489362 (-11000 2975);
PAINT SKYBLUE (-11000 2975);
FORCEPROP 1 LAST MATERIAL X6S
J 0
(-11000 2925);
DISPLAY 0.489362 (-11000 2925);
PAINT SKYBLUE (-11000 2925);
FORCEPROP 2 LAST CDS_LIB pure_quanta
J 0
(-11050 3025);
DISPLAY INVISIBLE (-11050 3025);
FORCEPROP 1 LAST PATH I10
J 0
(-11000 3175);
DISPLAY 0.978723 (-11000 3175);
PAINT WHITE (-11000 3175);
DISPLAY INVISIBLE (-11000 3175);
FORCEPROP 1 LAST PART_NUMBER CH5222KEB01
J 0
(-11000 2875);
DISPLAY 0.489362 (-11000 2875);
PAINT SKYBLUE (-11000 2875);
DISPLAY INVISIBLE (-11000 2875);
FORCEADD UNIVERSAL_GND..1
(-10700 3325);
FORCEPROP 3 LASTPIN (-10700 3375) SIG_NAME GND\g
J 0
(-10690 3385);
DISPLAY 0.659574 (-10690 3385);
PAINT MONO (-10690 3385);
DISPLAY INVISIBLE (-10690 3385);
FORCEPROP 2 LAST CDS_LIB pure_quanta_power
J 0
(-10700 3325);
DISPLAY INVISIBLE (-10700 3325);
FORCEPROP 1 LAST HDL_POWER GND
J 1
(-10675 3250);
DISPLAY 0.872340 (-10675 3250);
PAINT GREEN (-10675 3250);
DISPLAY INVISIBLE (-10675 3250);
FORCEPROP 1 LAST PATH I11
J 0
(-10625 3325);
DISPLAY 0.872340 (-10625 3325);
PAINT AQUA (-10625 3325);
DISPLAY INVISIBLE (-10625 3325);
FORCEADD Q_RES..2
(-11050 3575);
FORCEPROP 1 LAST LOCATION PR107
J 0
(-11005 3700);
DISPLAY 0.489362 (-11005 3700);
PAINT SKYBLUE (-11005 3700);
FORCEPROP 0 LAST $SEC 1
J 0
(-11000 3750);
DISPLAY 0.680851 (-11000 3750);
PAINT MONO (-11000 3750);
DISPLAY INVISIBLE (-11000 3750);
FORCEPROP 0 LAST CDS_SEC 1
J 0
(-11000 3750);
DISPLAY 1.021277 (-11000 3750);
DISPLAY INVISIBLE (-11000 3750);
FORCEPROP 1 LASTPIN (-11050 3675) $PN 1
J 0
(-11045 3637);
DISPLAY 0.489362 (-11045 3637);
PAINT MONO (-11045 3637);
FORCEPROP 1 LASTPIN (-11050 3475) $PN 2
J 0
(-11045 3485);
DISPLAY 0.489362 (-11045 3485);
PAINT MONO (-11045 3485);
FORCEPROP 1 LAST WATTAGE 1/16W
J 0
(-11000 3550);
DISPLAY 0.489362 (-11000 3550);
PAINT SKYBLUE (-11000 3550);
FORCEPROP 1 LAST MATERIAL CHIP
J 0
(-11000 3500);
DISPLAY 0.489362 (-11000 3500);
PAINT SKYBLUE (-11000 3500);
FORCEPROP 1 LAST TOLERANCE 1%
J 0
(-11000 3600);
DISPLAY 0.489362 (-11000 3600);
PAINT SKYBLUE (-11000 3600);
FORCEPROP 1 LAST VALUE 2.2
J 0
(-11000 3650);
DISPLAY 0.489362 (-11000 3650);
PAINT SKYBLUE (-11000 3650);
FORCEPROP 1 LAST PACK_TYPE 0402LF
J 0
(-11000 3400);
DISPLAY 0.489362 (-11000 3400);
PAINT SKYBLUE (-11000 3400);
FORCEPROP 2 LAST CDS_LIB pure_quanta
J 0
(-11050 3575);
DISPLAY INVISIBLE (-11050 3575);
FORCEPROP 1 LAST PATH I12
J 0
(-11000 3750);
DISPLAY 0.978723 (-11000 3750);
PAINT WHITE (-11000 3750);
DISPLAY INVISIBLE (-11000 3750);
FORCEPROP 1 LAST PART_NUMBER CS-2202FB01
J 0
(-11000 3450);
DISPLAY 0.489362 (-11000 3450);
PAINT SKYBLUE (-11000 3450);
DISPLAY INVISIBLE (-11000 3450);
FORCEADD Q_CAP..1
(-10700 3600);
FORCEPROP 1 LAST LOCATION PC173_IOP0_4
J 0
(-10650 3700);
DISPLAY 0.489362 (-10650 3700);
PAINT SKYBLUE (-10650 3700);
FORCEPROP 0 LAST $SEC 1
J 0
(-10650 3750);
DISPLAY 0.680851 (-10650 3750);
PAINT MONO (-10650 3750);
DISPLAY INVISIBLE (-10650 3750);
FORCEPROP 0 LAST CDS_SEC 1
J 0
(-10650 3750);
DISPLAY 1.021277 (-10650 3750);
DISPLAY INVISIBLE (-10650 3750);
FORCEPROP 1 LASTPIN (-10700 3700) $PN 1
J 0
(-10690 3680);
DISPLAY 0.489362 (-10690 3680);
PAINT MONO (-10690 3680);
FORCEPROP 1 LASTPIN (-10700 3500) $PN 2
J 0
(-10690 3480);
DISPLAY 0.489362 (-10690 3480);
PAINT MONO (-10690 3480);
FORCEPROP 1 LAST PACK_TYPE C0402
J 0
(-10650 3400);
DISPLAY 0.489362 (-10650 3400);
PAINT SKYBLUE (-10650 3400);
FORCEPROP 1 LAST VOLTAGE 10V
J 0
(-10650 3600);
DISPLAY 0.489362 (-10650 3600);
PAINT SKYBLUE (-10650 3600);
FORCEPROP 1 LAST VALUE 2.2UF
J 0
(-10650 3650);
DISPLAY 0.489362 (-10650 3650);
PAINT SKYBLUE (-10650 3650);
FORCEPROP 1 LAST TOLERANCE 10%
J 0
(-10650 3550);
DISPLAY 0.489362 (-10650 3550);
PAINT SKYBLUE (-10650 3550);
FORCEPROP 1 LAST MATERIAL X6S
J 0
(-10650 3500);
DISPLAY 0.489362 (-10650 3500);
PAINT SKYBLUE (-10650 3500);
FORCEPROP 2 LAST CDS_LIB pure_quanta
J 0
(-10700 3600);
DISPLAY INVISIBLE (-10700 3600);
FORCEPROP 1 LAST PATH I13
J 0
(-10650 3750);
DISPLAY 0.978723 (-10650 3750);
PAINT WHITE (-10650 3750);
DISPLAY INVISIBLE (-10650 3750);
FORCEPROP 1 LAST PART_NUMBER CH5222KEB01
J 0
(-10650 3450);
DISPLAY 0.489362 (-10650 3450);
PAINT SKYBLUE (-10650 3450);
DISPLAY INVISIBLE (-10650 3450);
FORCEADD VCC_CORE..1
(-11050 4000);
FORCEPROP 3 LASTPIN (-11050 3950) SIG_NAME PVDDCR_CPU1_P0_PVCC\g
J 0
(-11040 3960);
DISPLAY 0.659574 (-11040 3960);
PAINT MONO (-11040 3960);
DISPLAY INVISIBLE (-11040 3960);
FORCEPROP 1 LAST HDL_POWER PVDDCR_CPU1_P0_PVCC
J 1
(-11050 4050);
DISPLAY 0.489362 (-11050 4050);
PAINT GREEN (-11050 4050);
FORCEPROP 2 LAST CDS_LIB pure_quanta_power
J 0
(-11050 4000);
DISPLAY INVISIBLE (-11050 4000);
FORCEPROP 1 LAST PATH I14
J 0
(-11000 4025);
DISPLAY 0.872340 (-11000 4025);
PAINT AQUA (-11000 4025);
DISPLAY INVISIBLE (-11000 4025);
FORCEADD UNIVERSAL_GND..1
(-8700 1900);
FORCEPROP 3 LASTPIN (-8700 1950) SIG_NAME GND\g
J 0
(-8690 1960);
DISPLAY 0.659574 (-8690 1960);
PAINT MONO (-8690 1960);
DISPLAY INVISIBLE (-8690 1960);
FORCEPROP 2 LAST CDS_LIB pure_quanta_power
J 0
(-8700 1900);
PAINT MONO (-8700 1900);
DISPLAY INVISIBLE (-8700 1900);
FORCEPROP 1 LAST HDL_POWER GND
J 1
(-8675 1825);
DISPLAY 0.872340 (-8675 1825);
PAINT GREEN (-8675 1825);
DISPLAY INVISIBLE (-8675 1825);
FORCEPROP 1 LAST PATH I15
J 0
(-8625 1900);
DISPLAY 0.872340 (-8625 1900);
PAINT AQUA (-8625 1900);
DISPLAY INVISIBLE (-8625 1900);
FORCEADD Q_RES..1
(-8225 2975);
FORCEPROP 1 LAST LOCATION PR109
J 0
(-8475 3050);
DISPLAY 0.489362 (-8475 3050);
PAINT SKYBLUE (-8475 3050);
FORCEPROP 0 LAST $SEC 1
J 0
(-7950 3075);
DISPLAY 0.680851 (-7950 3075);
PAINT MONO (-7950 3075);
DISPLAY INVISIBLE (-7950 3075);
FORCEPROP 0 LAST CDS_SEC 1
J 0
(-7950 3075);
DISPLAY 1.021277 (-7950 3075);
DISPLAY INVISIBLE (-7950 3075);
FORCEPROP 1 LASTPIN (-8325 2975) $PN 1
J 0
(-8313 2987);
DISPLAY 0.787234 (-8313 2987);
PAINT MONO (-8313 2987);
DISPLAY INVISIBLE (-8313 2987);
FORCEPROP 1 LASTPIN (-8125 2975) $PN 2
J 0
(-8163 2987);
DISPLAY 0.787234 (-8163 2987);
PAINT MONO (-8163 2987);
DISPLAY INVISIBLE (-8163 2987);
FORCEPROP 1 LAST MATERIAL CHIP
J 0
(-8375 2900);
DISPLAY 0.489362 (-8375 2900);
PAINT SKYBLUE (-8375 2900);
FORCEPROP 1 LAST PACK_TYPE 0402LF
J 0
(-7825 2900);
DISPLAY 0.489362 (-7825 2900);
PAINT SKYBLUE (-7825 2900);
FORCEPROP 1 LAST TOLERANCE 1%
J 0
(-8225 3050);
DISPLAY 0.489362 (-8225 3050);
PAINT SKYBLUE (-8225 3050);
FORCEPROP 1 LAST WATTAGE 1/16W
J 2
(-7950 3050);
DISPLAY 0.489362 (-7950 3050);
PAINT SKYBLUE (-7950 3050);
FORCEPROP 1 LAST VALUE 5.6
J 2
(-8275 3050);
DISPLAY 0.489362 (-8275 3050);
PAINT SKYBLUE (-8275 3050);
FORCEPROP 2 LAST CDS_LIB pure_quanta
J 0
(-8225 2975);
DISPLAY INVISIBLE (-8225 2975);
FORCEPROP 1 LAST PATH I16
J 0
(-8275 3125);
DISPLAY 0.978723 (-8275 3125);
PAINT WHITE (-8275 3125);
DISPLAY INVISIBLE (-8275 3125);
FORCEPROP 1 LAST PART_NUMBER CS-5602FB01
J 0
(-8200 2900);
DISPLAY 0.489362 (-8200 2900);
PAINT SKYBLUE (-8200 2900);
DISPLAY INVISIBLE (-8200 2900);
FORCEADD Q_CAP..1
(-8475 3600);
FORCEPROP 1 LAST LOCATION PC178_4
J 0
(-8400 3725);
DISPLAY 0.489362 (-8400 3725);
PAINT SKYBLUE (-8400 3725);
FORCEPROP 0 LAST $SEC 1
J 0
(-8425 3750);
DISPLAY 0.680851 (-8425 3750);
PAINT MONO (-8425 3750);
DISPLAY INVISIBLE (-8425 3750);
FORCEPROP 0 LAST CDS_SEC 1
J 0
(-8425 3750);
DISPLAY 1.021277 (-8425 3750);
DISPLAY INVISIBLE (-8425 3750);
FORCEPROP 1 LASTPIN (-8475 3700) $PN 1
J 0
(-8465 3680);
DISPLAY 0.489362 (-8465 3680);
PAINT MONO (-8465 3680);
FORCEPROP 1 LASTPIN (-8475 3500) $PN 2
J 0
(-8465 3480);
DISPLAY 0.489362 (-8465 3480);
PAINT MONO (-8465 3480);
FORCEPROP 1 LAST PACK_TYPE 0402
J 0
(-8400 3425);
DISPLAY 0.489362 (-8400 3425);
PAINT SKYBLUE (-8400 3425);
FORCEPROP 1 LAST VOLTAGE 25V
J 0
(-8400 3625);
DISPLAY 0.489362 (-8400 3625);
PAINT SKYBLUE (-8400 3625);
FORCEPROP 1 LAST VALUE 0.1UF
J 0
(-8400 3675);
DISPLAY 0.489362 (-8400 3675);
PAINT SKYBLUE (-8400 3675);
FORCEPROP 1 LAST TOLERANCE 10%
J 0
(-8400 3575);
DISPLAY 0.489362 (-8400 3575);
PAINT SKYBLUE (-8400 3575);
FORCEPROP 1 LAST MATERIAL X7R
J 0
(-8400 3525);
DISPLAY 0.489362 (-8400 3525);
PAINT SKYBLUE (-8400 3525);
FORCEPROP 2 LAST CDS_LIB pure_quanta
J 0
(-8475 3600);
DISPLAY INVISIBLE (-8475 3600);
FORCEPROP 1 LAST PATH I17
J 0
(-8425 3750);
DISPLAY 0.978723 (-8425 3750);
PAINT WHITE (-8425 3750);
DISPLAY INVISIBLE (-8425 3750);
FORCEPROP 1 LAST PART_NUMBER CH4104K1B00
J 0
(-8400 3475);
DISPLAY 0.489362 (-8400 3475);
PAINT SKYBLUE (-8400 3475);
DISPLAY INVISIBLE (-8400 3475);
FORCEADD UNIVERSAL_GND..1
(-11925 4850);
FORCEPROP 3 LASTPIN (-11925 4900) SIG_NAME GND\g
J 0
(-11915 4910);
DISPLAY 0.659574 (-11915 4910);
PAINT MONO (-11915 4910);
DISPLAY INVISIBLE (-11915 4910);
FORCEPROP 2 LAST CDS_LIB pure_quanta_power
J 0
(-11925 4850);
DISPLAY INVISIBLE (-11925 4850);
FORCEPROP 1 LAST HDL_POWER GND
J 1
(-11900 4775);
DISPLAY 0.872340 (-11900 4775);
PAINT GREEN (-11900 4775);
DISPLAY INVISIBLE (-11900 4775);
FORCEPROP 1 LAST PATH I18
J 0
(-11850 4850);
DISPLAY 0.872340 (-11850 4850);
PAINT AQUA (-11850 4850);
DISPLAY INVISIBLE (-11850 4850);
FORCEADD Q_CAP..1
(-11925 5050);
FORCEPROP 1 LAST LOCATION PC175_9
J 0
(-11875 5150);
DISPLAY 0.489362 (-11875 5150);
PAINT SKYBLUE (-11875 5150);
FORCEPROP 0 LAST $SEC 1
J 0
(-11875 5175);
DISPLAY 0.680851 (-11875 5175);
PAINT MONO (-11875 5175);
DISPLAY INVISIBLE (-11875 5175);
FORCEPROP 0 LAST CDS_SEC 1
J 0
(-11675 5100);
DISPLAY 1.021277 (-11675 5100);
DISPLAY INVISIBLE (-11675 5100);
FORCEPROP 1 LASTPIN (-11925 5150) $PN 1
J 0
(-11915 5130);
DISPLAY 0.489362 (-11915 5130);
PAINT MONO (-11915 5130);
FORCEPROP 1 LASTPIN (-11925 4950) $PN 2
J 0
(-11915 4930);
DISPLAY 0.489362 (-11915 4930);
PAINT MONO (-11915 4930);
FORCEPROP 1 LAST PACK_TYPE 0402
J 0
(-11875 4850);
DISPLAY 0.489362 (-11875 4850);
PAINT SKYBLUE (-11875 4850);
FORCEPROP 1 LAST VOLTAGE 25V
J 0
(-11875 5050);
DISPLAY 0.489362 (-11875 5050);
PAINT SKYBLUE (-11875 5050);
FORCEPROP 1 LAST VALUE 0.1UF
J 0
(-11875 5100);
DISPLAY 0.489362 (-11875 5100);
PAINT SKYBLUE (-11875 5100);
FORCEPROP 1 LAST TOLERANCE 10%
J 0
(-11875 5000);
DISPLAY 0.489362 (-11875 5000);
PAINT SKYBLUE (-11875 5000);
FORCEPROP 1 LAST MATERIAL X7R
J 0
(-11875 4950);
DISPLAY 0.489362 (-11875 4950);
PAINT SKYBLUE (-11875 4950);
FORCEPROP 2 LAST CDS_LIB pure_quanta
J 0
(-11925 5050);
DISPLAY INVISIBLE (-11925 5050);
FORCEPROP 1 LAST PATH I19
J 0
(-11875 5200);
DISPLAY 0.978723 (-11875 5200);
PAINT WHITE (-11875 5200);
DISPLAY INVISIBLE (-11875 5200);
FORCEPROP 1 LAST PART_NUMBER CH4104K1B00
J 0
(-11875 4900);
DISPLAY 0.489362 (-11875 4900);
PAINT SKYBLUE (-11875 4900);
DISPLAY INVISIBLE (-11875 4900);
FORCEADD UNIVERSAL_GND..1
(-11900 2050);
FORCEPROP 3 LASTPIN (-11900 2100) SIG_NAME GND\g
J 0
(-11890 2110);
DISPLAY 0.659574 (-11890 2110);
PAINT MONO (-11890 2110);
DISPLAY INVISIBLE (-11890 2110);
FORCEPROP 2 LAST CDS_LIB pure_quanta_power
J 0
(-11900 2050);
DISPLAY INVISIBLE (-11900 2050);
FORCEPROP 1 LAST HDL_POWER GND
J 1
(-11875 1975);
DISPLAY 0.872340 (-11875 1975);
PAINT GREEN (-11875 1975);
DISPLAY INVISIBLE (-11875 1975);
FORCEPROP 1 LAST PATH I2
J 0
(-11825 2050);
DISPLAY 0.872340 (-11825 2050);
PAINT AQUA (-11825 2050);
DISPLAY INVISIBLE (-11825 2050);
FORCEADD UNIVERSAL_GND..1
(-11350 4750);
FORCEPROP 3 LASTPIN (-11350 4800) SIG_NAME GND\g
J 0
(-11340 4810);
DISPLAY 0.659574 (-11340 4810);
PAINT MONO (-11340 4810);
DISPLAY INVISIBLE (-11340 4810);
FORCEPROP 2 LAST CDS_LIB pure_quanta_power
J 0
(-11350 4750);
PAINT MONO (-11350 4750);
DISPLAY INVISIBLE (-11350 4750);
FORCEPROP 1 LAST HDL_POWER GND
J 1
(-11325 4675);
DISPLAY 0.872340 (-11325 4675);
PAINT GREEN (-11325 4675);
DISPLAY INVISIBLE (-11325 4675);
FORCEPROP 1 LAST PATH I20
J 0
(-11275 4750);
DISPLAY 0.872340 (-11275 4750);
PAINT AQUA (-11275 4750);
DISPLAY INVISIBLE (-11275 4750);
FORCEADD Q_RES..2
R 2
(-11350 4975);
FORCEPROP 1 LAST LOCATION PR106
J 2
(-11395 5100);
DISPLAY 0.489362 (-11395 5100);
PAINT SKYBLUE (-11395 5100);
FORCEPROP 0 LAST $SEC 1
J 2
(-11400 5150);
DISPLAY 0.680851 (-11400 5150);
PAINT MONO (-11400 5150);
DISPLAY INVISIBLE (-11400 5150);
FORCEPROP 0 LAST CDS_SEC 1
J 2
(-11400 5150);
DISPLAY 1.021277 (-11400 5150);
DISPLAY INVISIBLE (-11400 5150);
FORCEPROP 1 LASTPIN (-11350 5075) $PN 1
J 2
(-11355 5037);
DISPLAY 0.489362 (-11355 5037);
PAINT MONO (-11355 5037);
FORCEPROP 1 LASTPIN (-11350 4875) $PN 2
J 2
(-11355 4885);
DISPLAY 0.489362 (-11355 4885);
PAINT MONO (-11355 4885);
FORCEPROP 1 LAST PACK_TYPE 0402LF
J 2
(-11400 4800);
DISPLAY 0.489362 (-11400 4800);
PAINT SKYBLUE (-11400 4800);
FORCEPROP 1 LAST MATERIAL EMPTY
J 2
(-11400 4900);
DISPLAY 0.489362 (-11400 4900);
PAINT RED (-11400 4900);
FORCEPROP 1 LAST WATTAGE 1/16W
J 2
(-11400 4950);
DISPLAY 0.489362 (-11400 4950);
PAINT SKYBLUE (-11400 4950);
FORCEPROP 1 LAST TOLERANCE 1%
J 2
(-11405 5000);
DISPLAY 0.489362 (-11405 5000);
PAINT SKYBLUE (-11405 5000);
FORCEPROP 1 LAST VALUE 8.87K
J 2
(-11405 5050);
DISPLAY 0.489362 (-11405 5050);
PAINT SKYBLUE (-11405 5050);
FORCEPROP 2 LAST CDS_LIB pure_quanta
J 2
(-11350 4975);
DISPLAY INVISIBLE (-11350 4975);
FORCEPROP 1 LAST PATH I21
J 2
(-11400 5150);
DISPLAY 0.978723 (-11400 5150);
PAINT WHITE (-11400 5150);
DISPLAY INVISIBLE (-11400 5150);
FORCEPROP 1 LAST PART_NUMBER CS28872FB01
J 2
(-11400 4850);
DISPLAY 0.489362 (-11400 4850);
PAINT SKYBLUE (-11400 4850);
DISPLAY INVISIBLE (-11400 4850);
FORCEADD OFFPAGE..1
(-10875 4825);
FORCEPROP 2 LAST $XR0 200 
J 0
(-11157 4825);
DISPLAY 0.638298 (-11157 4825);
PAINT MONO (-11157 4825);
FORCEPROP 2 LAST CDS_LIB standard
J 0
(-10875 4825);
DISPLAY INVISIBLE (-10875 4825);
FORCEPROP 1 LAST OFFPAGE TRUE
J 0
(-10550 4700);
DISPLAY 0.872340 (-10550 4700);
PAINT GREEN (-10550 4700);
DISPLAY INVISIBLE (-10550 4700);
FORCEPROP 1 LAST COMMENT_BODY TRUE
J 0
(-10750 4725);
DISPLAY 0.872340 (-10750 4725);
PAINT GREEN (-10750 4725);
DISPLAY INVISIBLE (-10750 4725);
FORCEPROP 2 LAST PATH I22
J 0
(-11125 4875);
DISPLAY 0.680851 (-11125 4875);
DISPLAY INVISIBLE (-11125 4875);
FORCEADD OFFPAGE..5
(-10875 4925);
FORCEPROP 2 LAST $XR2 200 
J 0
(-11130 4961);
DISPLAY 0.638298 (-11130 4961);
PAINT MONO (-11130 4961);
FORCEPROP 2 LAST $XR1 206 
J 0
(-11130 4889);
DISPLAY 0.638298 (-11130 4889);
PAINT MONO (-11130 4889);
FORCEPROP 2 LAST $XR0 205 
J 0
(-11130 4925);
DISPLAY 0.638298 (-11130 4925);
PAINT MONO (-11130 4925);
FORCEPROP 2 LAST CDS_LIB standard
J 0
(-10875 4925);
DISPLAY INVISIBLE (-10875 4925);
FORCEPROP 1 LAST OFFPAGE TRUE
J 0
(-10550 4800);
DISPLAY 0.872340 (-10550 4800);
PAINT GREEN (-10550 4800);
DISPLAY INVISIBLE (-10550 4800);
FORCEPROP 1 LAST COMMENT_BODY TRUE
J 0
(-10775 4850);
DISPLAY 0.872340 (-10775 4850);
PAINT GREEN (-10775 4850);
DISPLAY INVISIBLE (-10775 4850);
FORCEPROP 2 LAST PATH I23
J 0
(-11150 5000);
DISPLAY 0.680851 (-11150 5000);
DISPLAY INVISIBLE (-11150 5000);
FORCEADD OFFPAGE..1
(-10875 5325);
FORCEPROP 2 LAST $XR5 206 
J 0
(-11757 5325);
DISPLAY 0.638298 (-11757 5325);
PAINT MONO (-11757 5325);
FORCEPROP 2 LAST $XR4 205 
J 0
(-11637 5325);
DISPLAY 0.638298 (-11637 5325);
PAINT MONO (-11637 5325);
FORCEPROP 2 LAST $XR3 203 
J 0
(-11517 5325);
DISPLAY 0.638298 (-11517 5325);
PAINT MONO (-11517 5325);
FORCEPROP 2 LAST $XR2 202 
J 0
(-11397 5325);
DISPLAY 0.638298 (-11397 5325);
PAINT MONO (-11397 5325);
FORCEPROP 2 LAST $XR1 201 
J 0
(-11277 5325);
DISPLAY 0.638298 (-11277 5325);
PAINT MONO (-11277 5325);
FORCEPROP 2 LAST $XR0 200 
J 0
(-11157 5325);
DISPLAY 0.638298 (-11157 5325);
PAINT MONO (-11157 5325);
FORCEPROP 2 LAST CDS_LIB standard
J 0
(-10875 5325);
DISPLAY INVISIBLE (-10875 5325);
FORCEPROP 1 LAST OFFPAGE TRUE
J 0
(-10550 5200);
DISPLAY 0.872340 (-10550 5200);
PAINT GREEN (-10550 5200);
DISPLAY INVISIBLE (-10550 5200);
FORCEPROP 1 LAST COMMENT_BODY TRUE
J 0
(-10750 5225);
DISPLAY 0.872340 (-10750 5225);
PAINT GREEN (-10750 5225);
DISPLAY INVISIBLE (-10750 5225);
FORCEPROP 2 LAST PATH I24
J 0
(-11125 5375);
DISPLAY 0.680851 (-11125 5375);
DISPLAY INVISIBLE (-11125 5375);
FORCEADD OFFPAGE..5
(-10875 5425);
FORCEPROP 2 LAST $XR0 200 
J 0
(-11130 5425);
DISPLAY 0.638298 (-11130 5425);
PAINT MONO (-11130 5425);
FORCEPROP 2 LAST CDS_LIB standard
J 0
(-10875 5425);
DISPLAY INVISIBLE (-10875 5425);
FORCEPROP 1 LAST OFFPAGE TRUE
J 0
(-10550 5300);
DISPLAY 0.872340 (-10550 5300);
PAINT GREEN (-10550 5300);
DISPLAY INVISIBLE (-10550 5300);
FORCEPROP 1 LAST COMMENT_BODY TRUE
J 0
(-10775 5350);
DISPLAY 0.872340 (-10775 5350);
PAINT GREEN (-10775 5350);
DISPLAY INVISIBLE (-10775 5350);
FORCEPROP 2 LAST PATH I25
J 0
(-11150 5475);
DISPLAY 0.680851 (-11150 5475);
DISPLAY INVISIBLE (-11150 5475);
FORCEADD UNIVERSAL_GND..1
(-11025 5525);
FORCEPROP 3 LASTPIN (-11025 5575) SIG_NAME GND\g
J 0
(-11015 5585);
DISPLAY 0.659574 (-11015 5585);
PAINT MONO (-11015 5585);
DISPLAY INVISIBLE (-11015 5585);
FORCEPROP 2 LAST CDS_LIB pure_quanta_power
J 0
(-11025 5525);
DISPLAY INVISIBLE (-11025 5525);
FORCEPROP 1 LAST HDL_POWER GND
J 1
(-11000 5450);
DISPLAY 0.872340 (-11000 5450);
PAINT GREEN (-11000 5450);
DISPLAY INVISIBLE (-11000 5450);
FORCEPROP 1 LAST PATH I26
J 0
(-10950 5525);
DISPLAY 0.872340 (-10950 5525);
PAINT AQUA (-10950 5525);
DISPLAY INVISIBLE (-10950 5525);
FORCEADD Q_CAP..1
(-11025 5725);
FORCEPROP 1 LAST LOCATION PC172
J 0
(-10975 5825);
DISPLAY 0.489362 (-10975 5825);
PAINT SKYBLUE (-10975 5825);
FORCEPROP 0 LAST $SEC 1
J 0
(-10975 5875);
DISPLAY 0.680851 (-10975 5875);
PAINT MONO (-10975 5875);
DISPLAY INVISIBLE (-10975 5875);
FORCEPROP 0 LAST CDS_SEC 1
J 0
(-10975 5875);
DISPLAY 1.021277 (-10975 5875);
DISPLAY INVISIBLE (-10975 5875);
FORCEPROP 1 LASTPIN (-11025 5825) $PN 1
J 0
(-11015 5805);
DISPLAY 0.489362 (-11015 5805);
PAINT MONO (-11015 5805);
FORCEPROP 1 LASTPIN (-11025 5625) $PN 2
J 0
(-11015 5605);
DISPLAY 0.489362 (-11015 5605);
PAINT MONO (-11015 5605);
FORCEPROP 1 LAST PACK_TYPE C0402
J 0
(-10975 5525);
DISPLAY 0.489362 (-10975 5525);
PAINT SKYBLUE (-10975 5525);
FORCEPROP 1 LAST VOLTAGE 10V
J 0
(-10975 5725);
DISPLAY 0.489362 (-10975 5725);
PAINT SKYBLUE (-10975 5725);
FORCEPROP 1 LAST VALUE 2.2UF
J 0
(-10975 5775);
DISPLAY 0.489362 (-10975 5775);
PAINT SKYBLUE (-10975 5775);
FORCEPROP 1 LAST TOLERANCE 10%
J 0
(-10975 5675);
DISPLAY 0.489362 (-10975 5675);
PAINT SKYBLUE (-10975 5675);
FORCEPROP 1 LAST MATERIAL X6S
J 0
(-10975 5625);
DISPLAY 0.489362 (-10975 5625);
PAINT SKYBLUE (-10975 5625);
FORCEPROP 2 LAST CDS_LIB pure_quanta
J 0
(-11025 5725);
DISPLAY INVISIBLE (-11025 5725);
FORCEPROP 1 LAST PATH I27
J 0
(-10975 5875);
DISPLAY 0.978723 (-10975 5875);
PAINT WHITE (-10975 5875);
DISPLAY INVISIBLE (-10975 5875);
FORCEPROP 1 LAST PART_NUMBER CH5222KEB01
J 0
(-10975 5575);
DISPLAY 0.489362 (-10975 5575);
PAINT SKYBLUE (-10975 5575);
DISPLAY INVISIBLE (-10975 5575);
FORCEADD Q_RES..2
(-11025 6275);
FORCEPROP 1 LAST LOCATION PR108
J 0
(-10980 6400);
DISPLAY 0.489362 (-10980 6400);
PAINT SKYBLUE (-10980 6400);
FORCEPROP 0 LAST $SEC 1
J 0
(-10975 6450);
DISPLAY 0.680851 (-10975 6450);
PAINT MONO (-10975 6450);
DISPLAY INVISIBLE (-10975 6450);
FORCEPROP 0 LAST CDS_SEC 1
J 0
(-10975 6450);
DISPLAY 1.021277 (-10975 6450);
DISPLAY INVISIBLE (-10975 6450);
FORCEPROP 1 LASTPIN (-11025 6375) $PN 1
J 0
(-11020 6337);
DISPLAY 0.489362 (-11020 6337);
PAINT MONO (-11020 6337);
FORCEPROP 1 LASTPIN (-11025 6175) $PN 2
J 0
(-11020 6185);
DISPLAY 0.489362 (-11020 6185);
PAINT MONO (-11020 6185);
FORCEPROP 1 LAST WATTAGE 1/16W
J 0
(-10975 6250);
DISPLAY 0.489362 (-10975 6250);
PAINT SKYBLUE (-10975 6250);
FORCEPROP 1 LAST MATERIAL CHIP
J 0
(-10975 6200);
DISPLAY 0.489362 (-10975 6200);
PAINT SKYBLUE (-10975 6200);
FORCEPROP 1 LAST TOLERANCE 1%
J 0
(-10975 6300);
DISPLAY 0.489362 (-10975 6300);
PAINT SKYBLUE (-10975 6300);
FORCEPROP 1 LAST VALUE 2.2
J 0
(-10975 6350);
DISPLAY 0.489362 (-10975 6350);
PAINT SKYBLUE (-10975 6350);
FORCEPROP 1 LAST PACK_TYPE 0402LF
J 0
(-10975 6100);
DISPLAY 0.489362 (-10975 6100);
PAINT SKYBLUE (-10975 6100);
FORCEPROP 2 LAST CDS_LIB pure_quanta
J 0
(-11025 6275);
DISPLAY INVISIBLE (-11025 6275);
FORCEPROP 1 LAST PATH I28
J 0
(-10975 6450);
DISPLAY 0.978723 (-10975 6450);
PAINT WHITE (-10975 6450);
DISPLAY INVISIBLE (-10975 6450);
FORCEPROP 1 LAST PART_NUMBER CS-2202FB01
J 0
(-10975 6150);
DISPLAY 0.489362 (-10975 6150);
PAINT SKYBLUE (-10975 6150);
DISPLAY INVISIBLE (-10975 6150);
FORCEADD UNIVERSAL_GND..1
(-10675 6025);
FORCEPROP 3 LASTPIN (-10675 6075) SIG_NAME GND\g
J 0
(-10665 6085);
DISPLAY 0.659574 (-10665 6085);
PAINT MONO (-10665 6085);
DISPLAY INVISIBLE (-10665 6085);
FORCEPROP 2 LAST CDS_LIB pure_quanta_power
J 0
(-10675 6025);
DISPLAY INVISIBLE (-10675 6025);
FORCEPROP 1 LAST HDL_POWER GND
J 1
(-10650 5950);
DISPLAY 0.872340 (-10650 5950);
PAINT GREEN (-10650 5950);
DISPLAY INVISIBLE (-10650 5950);
FORCEPROP 1 LAST PATH I29
J 0
(-10600 6025);
DISPLAY 0.872340 (-10600 6025);
PAINT AQUA (-10600 6025);
DISPLAY INVISIBLE (-10600 6025);
FORCEADD UNIVERSAL_GND..1
(-11375 1900);
FORCEPROP 3 LASTPIN (-11375 1950) SIG_NAME GND\g
J 0
(-11365 1960);
DISPLAY 0.659574 (-11365 1960);
PAINT MONO (-11365 1960);
DISPLAY INVISIBLE (-11365 1960);
FORCEPROP 2 LAST CDS_LIB pure_quanta_power
J 0
(-11375 1900);
PAINT MONO (-11375 1900);
DISPLAY INVISIBLE (-11375 1900);
FORCEPROP 1 LAST HDL_POWER GND
J 1
(-11350 1825);
DISPLAY 0.872340 (-11350 1825);
PAINT GREEN (-11350 1825);
DISPLAY INVISIBLE (-11350 1825);
FORCEPROP 1 LAST PATH I3
J 0
(-11300 1900);
DISPLAY 0.872340 (-11300 1900);
PAINT AQUA (-11300 1900);
DISPLAY INVISIBLE (-11300 1900);
FORCEADD Q_CAP..1
(-10675 6300);
FORCEPROP 1 LAST LOCATION PC174_IOP0_3
J 0
(-10625 6400);
DISPLAY 0.489362 (-10625 6400);
PAINT SKYBLUE (-10625 6400);
FORCEPROP 0 LAST $SEC 1
J 0
(-10625 6450);
DISPLAY 0.680851 (-10625 6450);
PAINT MONO (-10625 6450);
DISPLAY INVISIBLE (-10625 6450);
FORCEPROP 0 LAST CDS_SEC 1
J 0
(-10625 6450);
DISPLAY 1.021277 (-10625 6450);
DISPLAY INVISIBLE (-10625 6450);
FORCEPROP 1 LASTPIN (-10675 6400) $PN 1
J 0
(-10665 6380);
DISPLAY 0.489362 (-10665 6380);
PAINT MONO (-10665 6380);
FORCEPROP 1 LASTPIN (-10675 6200) $PN 2
J 0
(-10665 6180);
DISPLAY 0.489362 (-10665 6180);
PAINT MONO (-10665 6180);
FORCEPROP 1 LAST PACK_TYPE C0402
J 0
(-10625 6100);
DISPLAY 0.489362 (-10625 6100);
PAINT SKYBLUE (-10625 6100);
FORCEPROP 1 LAST VOLTAGE 10V
J 0
(-10625 6300);
DISPLAY 0.489362 (-10625 6300);
PAINT SKYBLUE (-10625 6300);
FORCEPROP 1 LAST VALUE 2.2UF
J 0
(-10625 6350);
DISPLAY 0.489362 (-10625 6350);
PAINT SKYBLUE (-10625 6350);
FORCEPROP 1 LAST TOLERANCE 10%
J 0
(-10625 6250);
DISPLAY 0.489362 (-10625 6250);
PAINT SKYBLUE (-10625 6250);
FORCEPROP 1 LAST MATERIAL X6S
J 0
(-10625 6200);
DISPLAY 0.489362 (-10625 6200);
PAINT SKYBLUE (-10625 6200);
FORCEPROP 2 LAST CDS_LIB pure_quanta
J 0
(-10675 6300);
DISPLAY INVISIBLE (-10675 6300);
FORCEPROP 1 LAST PATH I30
J 0
(-10625 6450);
DISPLAY 0.978723 (-10625 6450);
PAINT WHITE (-10625 6450);
DISPLAY INVISIBLE (-10625 6450);
FORCEPROP 1 LAST PART_NUMBER CH5222KEB01
J 0
(-10625 6150);
DISPLAY 0.489362 (-10625 6150);
PAINT SKYBLUE (-10625 6150);
DISPLAY INVISIBLE (-10625 6150);
FORCEADD VCC_CORE..1
(-11025 6700);
FORCEPROP 3 LASTPIN (-11025 6650) SIG_NAME PVDDCR_CPU1_P0_PVCC\g
J 0
(-11015 6660);
DISPLAY 0.659574 (-11015 6660);
PAINT MONO (-11015 6660);
DISPLAY INVISIBLE (-11015 6660);
FORCEPROP 1 LAST HDL_POWER PVDDCR_CPU1_P0_PVCC
J 1
(-11025 6750);
DISPLAY 0.489362 (-11025 6750);
PAINT GREEN (-11025 6750);
FORCEPROP 2 LAST CDS_LIB pure_quanta_power
J 0
(-11025 6700);
DISPLAY INVISIBLE (-11025 6700);
FORCEPROP 1 LAST PATH I31
J 0
(-10975 6725);
DISPLAY 0.872340 (-10975 6725);
PAINT AQUA (-10975 6725);
DISPLAY INVISIBLE (-10975 6725);
FORCEADD ISL99390FRZTR5935..1
(-9350 5425);
FORCEPROP 1 LAST LOCATION PU19
J 0
(-9650 6300);
DISPLAY 0.489362 (-9650 6300);
PAINT SKYBLUE (-9650 6300);
FORCEPROP 0 LAST $SEC 1
J 0
(-9650 6500);
DISPLAY 0.680851 (-9650 6500);
PAINT MONO (-9650 6500);
DISPLAY INVISIBLE (-9650 6500);
FORCEPROP 2 LAST CDS_SEC 1
J 0
(-9600 6425);
DISPLAY 1.021277 (-9600 6425);
DISPLAY INVISIBLE (-9600 6425);
FORCEPROP 0 LASTPIN (-8950 4975) $PN 2
J 0
(-8940 4985);
DISPLAY 0.489362 (-8940 4985);
PAINT MONO (-8940 4985);
FORCEPROP 0 LASTPIN (-8950 5775) $PN 33
J 0
(-8940 5785);
DISPLAY 0.489362 (-8940 5785);
PAINT MONO (-8940 5785);
FORCEPROP 0 LASTPIN (-9800 5175) $PN 31
J 2
(-9810 5185);
DISPLAY 0.489362 (-9810 5185);
PAINT MONO (-9810 5185);
FORCEPROP 0 LASTPIN (-9800 5575) $PN 35
J 2
(-9810 5585);
DISPLAY 0.489362 (-9810 5585);
PAINT MONO (-9810 5585);
FORCEPROP 0 LASTPIN (-8950 5125) $PN 6
J 0
(-8940 5135);
DISPLAY 0.489362 (-8940 5135);
PAINT MONO (-8940 5135);
FORCEPROP 0 LASTPIN (-8950 5075) $PN 41
J 0
(-8940 5085);
DISPLAY 0.489362 (-8940 5085);
PAINT MONO (-8940 5085);
FORCEPROP 0 LASTPIN (-9800 5425) $PN 38
J 2
(-9810 5435);
DISPLAY 0.489362 (-9810 5435);
PAINT MONO (-9810 5435);
FORCEPROP 0 LASTPIN (-9800 5125) $PN 37
J 2
(-9810 5135);
DISPLAY 0.489362 (-9810 5135);
PAINT MONO (-9810 5135);
FORCEPROP 0 LASTPIN (-8950 4925) $PN 5
J 0
(-8940 4935);
DISPLAY 0.489362 (-8940 4935);
PAINT MONO (-8940 4935);
FORCEPROP 0 LASTPIN (-8950 4875) $PN 7_9-20_24
J 0
(-8940 4885);
DISPLAY 0.489362 (-8940 4885);
PAINT MONO (-8940 4885);
FORCEPROP 0 LASTPIN (-8950 4825) $PN 40
J 0
(-8940 4835);
DISPLAY 0.489362 (-8940 4835);
PAINT MONO (-8940 4835);
FORCEPROP 0 LASTPIN (-8950 5525) $PN 32
J 0
(-8940 5535);
DISPLAY 0.489362 (-8940 5535);
PAINT MONO (-8940 5535);
FORCEPROP 0 LASTPIN (-9800 6075) $PN 4
J 2
(-9810 6085);
DISPLAY 0.489362 (-9810 6085);
PAINT MONO (-9810 6085);
FORCEPROP 0 LASTPIN (-9800 4825) $PN 34
J 2
(-9810 4835);
DISPLAY 0.489362 (-9810 4835);
PAINT MONO (-9810 4835);
FORCEPROP 0 LASTPIN (-9800 5325) $PN 39
J 2
(-9810 5335);
DISPLAY 0.489362 (-9810 5335);
PAINT MONO (-9810 5335);
FORCEPROP 0 LASTPIN (-8950 5425) $PN 10_19
J 0
(-8940 5435);
DISPLAY 0.489362 (-8940 5435);
PAINT MONO (-8940 5435);
FORCEPROP 0 LASTPIN (-9800 4925) $PN 36
J 2
(-9810 4935);
DISPLAY 0.489362 (-9810 4935);
PAINT MONO (-9810 4935);
FORCEPROP 0 LASTPIN (-9800 5775) $PN 3
J 2
(-9810 5785);
DISPLAY 0.489362 (-9810 5785);
PAINT MONO (-9810 5785);
FORCEPROP 0 LASTPIN (-8950 6075) $PN 25_29
J 0
(-8940 6085);
DISPLAY 0.489362 (-8940 6085);
PAINT MONO (-8940 6085);
FORCEPROP 0 LASTPIN (-8950 6025) $PN 30
J 0
(-8940 6035);
DISPLAY 0.489362 (-8940 6035);
PAINT MONO (-8940 6035);
FORCEPROP 0 LASTPIN (-8950 5175) $PN 1
J 0
(-8940 5185);
DISPLAY 0.489362 (-8940 5185);
PAINT MONO (-8940 5185);
FORCEPROP 2 LAST VALUE ISL99390FRZ-TR5935
J 0
(-9650 6400);
DISPLAY 0.489362 (-9650 6400);
PAINT SKYBLUE (-9650 6400);
FORCEPROP 1 LAST MATERIAL IC
J 0
(-9650 6150);
DISPLAY 0.489362 (-9650 6150);
PAINT SKYBLUE (-9650 6150);
FORCEPROP 2 LAST PART_TYPE SMLF
J 0
(-9650 6450);
DISPLAY 0.638298 (-9650 6450);
FORCEPROP 2 LAST CDS_LIB pure_quanta
J 0
(-9350 5425);
DISPLAY INVISIBLE (-9350 5425);
FORCEPROP 1 LAST NEEDS_NO_SIZE TRUE
J 0
(-9350 5425);
DISPLAY 0.723404 (-9350 5425);
PAINT GREEN (-9350 5425);
DISPLAY INVISIBLE (-9350 5425);
FORCEPROP 1 LAST CDS_LMAN_SYM_OUTLINE -300,700,250,-650
J 0
(-9350 5425);
DISPLAY 0.468085 (-9350 5425);
PAINT GREEN (-9350 5425);
DISPLAY INVISIBLE (-9350 5425);
FORCEPROP 1 LAST PATH I32
J 0
(-9350 5425);
DISPLAY 0.723404 (-9350 5425);
PAINT GREEN (-9350 5425);
DISPLAY INVISIBLE (-9350 5425);
FORCEPROP 1 LAST PART_NUMBER AL099390004
J 0
(-9650 6225);
DISPLAY 0.489362 (-9650 6225);
PAINT SKYBLUE (-9650 6225);
DISPLAY INVISIBLE (-9650 6225);
FORCEADD UNIVERSAL_GND..1
(-8700 4700);
FORCEPROP 3 LASTPIN (-8700 4750) SIG_NAME GND\g
J 0
(-8690 4760);
DISPLAY 0.659574 (-8690 4760);
PAINT MONO (-8690 4760);
DISPLAY INVISIBLE (-8690 4760);
FORCEPROP 2 LAST CDS_LIB pure_quanta_power
J 0
(-8700 4700);
PAINT MONO (-8700 4700);
DISPLAY INVISIBLE (-8700 4700);
FORCEPROP 1 LAST HDL_POWER GND
J 1
(-8675 4625);
DISPLAY 0.872340 (-8675 4625);
PAINT GREEN (-8675 4625);
DISPLAY INVISIBLE (-8675 4625);
FORCEPROP 1 LAST PATH I33
J 0
(-8625 4700);
DISPLAY 0.872340 (-8625 4700);
PAINT AQUA (-8625 4700);
DISPLAY INVISIBLE (-8625 4700);
FORCEADD Q_RES..1
(-8000 5775);
FORCEPROP 1 LAST LOCATION PR110
J 0
(-8025 5825);
DISPLAY 0.489362 (-8025 5825);
PAINT SKYBLUE (-8025 5825);
FORCEPROP 0 LAST $SEC 1
J 0
(-7725 5875);
DISPLAY 0.680851 (-7725 5875);
PAINT MONO (-7725 5875);
DISPLAY INVISIBLE (-7725 5875);
FORCEPROP 0 LAST CDS_SEC 1
J 0
(-7725 5875);
DISPLAY 1.021277 (-7725 5875);
DISPLAY INVISIBLE (-7725 5875);
FORCEPROP 1 LASTPIN (-8100 5775) $PN 1
J 0
(-8088 5787);
DISPLAY 0.787234 (-8088 5787);
PAINT MONO (-8088 5787);
DISPLAY INVISIBLE (-8088 5787);
FORCEPROP 1 LASTPIN (-7900 5775) $PN 2
J 0
(-7938 5787);
DISPLAY 0.787234 (-7938 5787);
PAINT MONO (-7938 5787);
DISPLAY INVISIBLE (-7938 5787);
FORCEPROP 1 LAST PACK_TYPE 0402LF
J 0
(-7950 5675);
DISPLAY 0.489362 (-7950 5675);
PAINT SKYBLUE (-7950 5675);
FORCEPROP 1 LAST TOLERANCE 1%
J 0
(-8125 5825);
DISPLAY 0.489362 (-8125 5825);
PAINT SKYBLUE (-8125 5825);
FORCEPROP 1 LAST WATTAGE 1/16W
J 2
(-7800 5800);
DISPLAY 0.489362 (-7800 5800);
PAINT SKYBLUE (-7800 5800);
FORCEPROP 1 LAST MATERIAL CHIP
J 0
(-7925 5725);
DISPLAY 0.489362 (-7925 5725);
PAINT SKYBLUE (-7925 5725);
FORCEPROP 1 LAST VALUE 5.6
J 2
(-8175 5825);
DISPLAY 0.489362 (-8175 5825);
PAINT SKYBLUE (-8175 5825);
FORCEPROP 2 LAST CDS_LIB pure_quanta
J 0
(-8000 5775);
DISPLAY INVISIBLE (-8000 5775);
FORCEPROP 1 LAST PATH I34
J 0
(-8050 5925);
DISPLAY 0.978723 (-8050 5925);
PAINT WHITE (-8050 5925);
DISPLAY INVISIBLE (-8050 5925);
FORCEPROP 1 LAST PART_NUMBER CS-5602FB01
J 0
(-8325 5725);
DISPLAY 0.489362 (-8325 5725);
PAINT SKYBLUE (-8325 5725);
DISPLAY INVISIBLE (-8325 5725);
FORCEADD Q_CAP..1
(-8500 6375);
FORCEPROP 1 LAST LOCATION PC177_3
J 0
(-8425 6525);
DISPLAY 0.489362 (-8425 6525);
PAINT SKYBLUE (-8425 6525);
FORCEPROP 0 LAST $SEC 1
J 0
(-8450 6525);
DISPLAY 0.680851 (-8450 6525);
PAINT MONO (-8450 6525);
DISPLAY INVISIBLE (-8450 6525);
FORCEPROP 0 LAST CDS_SEC 1
J 0
(-8450 6525);
DISPLAY 1.021277 (-8450 6525);
DISPLAY INVISIBLE (-8450 6525);
FORCEPROP 1 LASTPIN (-8500 6475) $PN 1
J 0
(-8490 6455);
DISPLAY 0.489362 (-8490 6455);
PAINT MONO (-8490 6455);
FORCEPROP 1 LASTPIN (-8500 6275) $PN 2
J 0
(-8490 6255);
DISPLAY 0.489362 (-8490 6255);
PAINT MONO (-8490 6255);
FORCEPROP 1 LAST PACK_TYPE 0402
J 0
(-8425 6225);
DISPLAY 0.489362 (-8425 6225);
PAINT SKYBLUE (-8425 6225);
FORCEPROP 1 LAST VALUE 0.1UF
J 0
(-8425 6475);
DISPLAY 0.489362 (-8425 6475);
PAINT SKYBLUE (-8425 6475);
FORCEPROP 1 LAST TOLERANCE 10%
J 0
(-8425 6375);
DISPLAY 0.489362 (-8425 6375);
PAINT SKYBLUE (-8425 6375);
FORCEPROP 1 LAST MATERIAL X7R
J 0
(-8425 6325);
DISPLAY 0.489362 (-8425 6325);
PAINT SKYBLUE (-8425 6325);
FORCEPROP 1 LAST VOLTAGE 25V
J 0
(-8425 6425);
DISPLAY 0.489362 (-8425 6425);
PAINT SKYBLUE (-8425 6425);
FORCEPROP 2 LAST CDS_LIB pure_quanta
J 0
(-8500 6375);
DISPLAY INVISIBLE (-8500 6375);
FORCEPROP 1 LAST PATH I35
J 0
(-8450 6525);
DISPLAY 0.978723 (-8450 6525);
PAINT WHITE (-8450 6525);
DISPLAY INVISIBLE (-8450 6525);
FORCEPROP 1 LAST PART_NUMBER CH4104K1B00
J 0
(-8425 6275);
DISPLAY 0.489362 (-8425 6275);
PAINT SKYBLUE (-8425 6275);
DISPLAY INVISIBLE (-8425 6275);
FORCEADD Q_CAP..1
(-8075 6375);
FORCEPROP 1 LAST LOCATION PC179_3
J 0
(-8025 6525);
DISPLAY 0.489362 (-8025 6525);
PAINT SKYBLUE (-8025 6525);
FORCEPROP 0 LAST $SEC 1
J 0
(-8025 6575);
DISPLAY 0.680851 (-8025 6575);
PAINT MONO (-8025 6575);
DISPLAY INVISIBLE (-8025 6575);
FORCEPROP 0 LAST CDS_SEC 1
J 0
(-8025 6575);
DISPLAY 1.021277 (-8025 6575);
DISPLAY INVISIBLE (-8025 6575);
FORCEPROP 1 LASTPIN (-8075 6475) $PN 1
J 0
(-8065 6455);
DISPLAY 0.489362 (-8065 6455);
PAINT MONO (-8065 6455);
FORCEPROP 1 LASTPIN (-8075 6275) $PN 2
J 0
(-8065 6255);
DISPLAY 0.489362 (-8065 6255);
PAINT MONO (-8065 6255);
FORCEPROP 1 LAST VOLTAGE 25V
J 0
(-8025 6425);
DISPLAY 0.489362 (-8025 6425);
PAINT SKYBLUE (-8025 6425);
FORCEPROP 1 LAST VALUE 1UF
J 0
(-8025 6475);
DISPLAY 0.489362 (-8025 6475);
PAINT SKYBLUE (-8025 6475);
FORCEPROP 1 LAST TOLERANCE 10%
J 0
(-8025 6375);
DISPLAY 0.489362 (-8025 6375);
PAINT SKYBLUE (-8025 6375);
FORCEPROP 1 LAST MATERIAL X6S
J 0
(-8025 6325);
DISPLAY 0.489362 (-8025 6325);
PAINT SKYBLUE (-8025 6325);
FORCEPROP 1 LAST PACK_TYPE C0402
J 0
(-8025 6275);
DISPLAY 0.489362 (-8025 6275);
PAINT SKYBLUE (-8025 6275);
FORCEPROP 2 LAST CDS_LIB pure_quanta
J 0
(-8075 6375);
DISPLAY INVISIBLE (-8075 6375);
FORCEPROP 1 LAST PATH I36
J 0
(-8025 6525);
DISPLAY 0.978723 (-8025 6525);
PAINT WHITE (-8025 6525);
DISPLAY INVISIBLE (-8025 6525);
FORCEPROP 1 LAST PART_NUMBER CH5104KEB02
J 0
(-8025 6225);
DISPLAY 0.489362 (-8025 6225);
PAINT SKYBLUE (-8025 6225);
DISPLAY INVISIBLE (-8025 6225);
FORCEADD UNIVERSAL_GND..1
(-7950 1675);
FORCEPROP 3 LASTPIN (-7950 1725) SIG_NAME GND\g
J 0
(-7940 1735);
DISPLAY 0.659574 (-7940 1735);
PAINT MONO (-7940 1735);
DISPLAY INVISIBLE (-7940 1735);
FORCEPROP 2 LAST CDS_LIB pure_quanta_power
J 0
(-7950 1675);
DISPLAY INVISIBLE (-7950 1675);
FORCEPROP 1 LAST HDL_POWER GND
J 1
(-7925 1600);
DISPLAY 0.872340 (-7925 1600);
PAINT GREEN (-7925 1600);
DISPLAY INVISIBLE (-7925 1600);
FORCEPROP 1 LAST PATH I37
J 0
(-7875 1675);
DISPLAY 0.872340 (-7875 1675);
PAINT AQUA (-7875 1675);
DISPLAY INVISIBLE (-7875 1675);
FORCEADD Q_RES..2
(-7950 1900);
FORCEPROP 1 LAST LOCATION PR291
J 0
(-7905 2025);
DISPLAY 0.489362 (-7905 2025);
PAINT SKYBLUE (-7905 2025);
FORCEPROP 0 LAST $SEC 1
J 0
(-7900 2075);
DISPLAY 0.680851 (-7900 2075);
PAINT MONO (-7900 2075);
DISPLAY INVISIBLE (-7900 2075);
FORCEPROP 0 LAST CDS_SEC 1
J 0
(-7900 2075);
DISPLAY 1.021277 (-7900 2075);
DISPLAY INVISIBLE (-7900 2075);
FORCEPROP 1 LASTPIN (-7950 2000) $PN 1
J 0
(-7945 1962);
DISPLAY 0.489362 (-7945 1962);
PAINT MONO (-7945 1962);
FORCEPROP 1 LASTPIN (-7950 1800) $PN 2
J 0
(-7945 1810);
DISPLAY 0.489362 (-7945 1810);
PAINT MONO (-7945 1810);
FORCEPROP 1 LAST PACK_TYPE 0402LF
J 0
(-7910 1725);
DISPLAY 0.489362 (-7910 1725);
PAINT SKYBLUE (-7910 1725);
FORCEPROP 1 LAST VALUE 1.5
J 0
(-7905 1975);
DISPLAY 0.489362 (-7905 1975);
PAINT SKYBLUE (-7905 1975);
FORCEPROP 1 LAST TOLERANCE 1%
J 0
(-7905 1925);
DISPLAY 0.489362 (-7905 1925);
PAINT SKYBLUE (-7905 1925);
FORCEPROP 1 LAST MATERIAL EMPTY
J 0
(-7910 1825);
DISPLAY 0.489362 (-7910 1825);
PAINT RED (-7910 1825);
FORCEPROP 1 LAST WATTAGE 1/8W
J 0
(-7910 1875);
DISPLAY 0.489362 (-7910 1875);
PAINT SKYBLUE (-7910 1875);
FORCEPROP 2 LAST CDS_LIB pure_quanta
J 0
(-7950 1900);
DISPLAY INVISIBLE (-7950 1900);
FORCEPROP 1 LAST PATH I38
J 0
(-7900 2075);
DISPLAY 0.978723 (-7900 2075);
PAINT WHITE (-7900 2075);
DISPLAY INVISIBLE (-7900 2075);
FORCEPROP 1 LAST PART_NUMBER CS-1504FB00
J 0
(-7910 1775);
DISPLAY 0.489362 (-7910 1775);
PAINT SKYBLUE (-7910 1775);
DISPLAY INVISIBLE (-7910 1775);
FORCEADD Q_CAP..1
(-7950 2425);
FORCEPROP 1 LAST LOCATION PC163
J 0
(-7900 2525);
DISPLAY 0.489362 (-7900 2525);
PAINT SKYBLUE (-7900 2525);
FORCEPROP 0 LAST $SEC 1
J 0
(-7900 2575);
DISPLAY 0.680851 (-7900 2575);
PAINT MONO (-7900 2575);
DISPLAY INVISIBLE (-7900 2575);
FORCEPROP 0 LAST CDS_SEC 1
J 0
(-7900 2575);
DISPLAY 1.021277 (-7900 2575);
DISPLAY INVISIBLE (-7900 2575);
FORCEPROP 1 LASTPIN (-7950 2525) $PN 1
J 0
(-7940 2505);
DISPLAY 0.489362 (-7940 2505);
PAINT MONO (-7940 2505);
FORCEPROP 1 LASTPIN (-7950 2325) $PN 2
J 0
(-7940 2305);
DISPLAY 0.489362 (-7940 2305);
PAINT MONO (-7940 2305);
FORCEPROP 1 LAST MATERIAL EMPTY
J 0
(-7900 2325);
DISPLAY 0.489362 (-7900 2325);
PAINT RED (-7900 2325);
FORCEPROP 1 LAST PACK_TYPE C0402
J 0
(-7900 2225);
DISPLAY 0.489362 (-7900 2225);
PAINT SKYBLUE (-7900 2225);
FORCEPROP 1 LAST TOLERANCE 10%
J 0
(-7900 2375);
DISPLAY 0.489362 (-7900 2375);
PAINT SKYBLUE (-7900 2375);
FORCEPROP 1 LAST VOLTAGE 50V
J 0
(-7900 2425);
DISPLAY 0.489362 (-7900 2425);
PAINT SKYBLUE (-7900 2425);
FORCEPROP 1 LAST VALUE 560PF
J 0
(-7900 2475);
DISPLAY 0.489362 (-7900 2475);
PAINT SKYBLUE (-7900 2475);
FORCEPROP 2 LAST CDS_LIB pure_quanta
J 0
(-7950 2425);
DISPLAY INVISIBLE (-7950 2425);
FORCEPROP 1 LAST PATH I39
J 0
(-7900 2575);
DISPLAY 0.978723 (-7900 2575);
PAINT WHITE (-7900 2575);
DISPLAY INVISIBLE (-7900 2575);
FORCEPROP 1 LAST PART_NUMBER CH1566K1B09
J 0
(-7900 2275);
DISPLAY 0.489362 (-7900 2275);
PAINT SKYBLUE (-7900 2275);
DISPLAY INVISIBLE (-7900 2275);
FORCEADD Q_RES..2
R 2
(-11375 2125);
FORCEPROP 1 LAST LOCATION PR105
J 2
(-11420 2250);
DISPLAY 0.489362 (-11420 2250);
PAINT SKYBLUE (-11420 2250);
FORCEPROP 0 LAST $SEC 1
J 2
(-11425 2300);
DISPLAY 0.680851 (-11425 2300);
PAINT MONO (-11425 2300);
DISPLAY INVISIBLE (-11425 2300);
FORCEPROP 0 LAST CDS_SEC 1
J 2
(-11425 2300);
DISPLAY 1.021277 (-11425 2300);
DISPLAY INVISIBLE (-11425 2300);
FORCEPROP 1 LASTPIN (-11375 2225) $PN 1
J 2
(-11380 2187);
DISPLAY 0.489362 (-11380 2187);
PAINT MONO (-11380 2187);
FORCEPROP 1 LASTPIN (-11375 2025) $PN 2
J 2
(-11380 2035);
DISPLAY 0.489362 (-11380 2035);
PAINT MONO (-11380 2035);
FORCEPROP 1 LAST WATTAGE 1/16W
J 2
(-11425 2100);
DISPLAY 0.489362 (-11425 2100);
PAINT SKYBLUE (-11425 2100);
FORCEPROP 1 LAST MATERIAL EMPTY
J 2
(-11425 2050);
DISPLAY 0.489362 (-11425 2050);
PAINT RED (-11425 2050);
FORCEPROP 1 LAST TOLERANCE 1%
J 2
(-11430 2150);
DISPLAY 0.489362 (-11430 2150);
PAINT SKYBLUE (-11430 2150);
FORCEPROP 1 LAST VALUE 8.87K
J 2
(-11430 2200);
DISPLAY 0.489362 (-11430 2200);
PAINT SKYBLUE (-11430 2200);
FORCEPROP 1 LAST PACK_TYPE 0402LF
J 2
(-11425 1950);
DISPLAY 0.489362 (-11425 1950);
PAINT SKYBLUE (-11425 1950);
FORCEPROP 2 LAST CDS_LIB pure_quanta
J 2
(-11375 2125);
DISPLAY INVISIBLE (-11375 2125);
FORCEPROP 1 LAST PATH I4
J 2
(-11425 2300);
DISPLAY 0.978723 (-11425 2300);
PAINT WHITE (-11425 2300);
DISPLAY INVISIBLE (-11425 2300);
FORCEPROP 1 LAST PART_NUMBER CS28872FB01
J 2
(-11425 2000);
DISPLAY 0.489362 (-11425 2000);
PAINT SKYBLUE (-11425 2000);
DISPLAY INVISIBLE (-11425 2000);
FORCEADD UNIVERSAL_GND..1
(-7525 2275);
FORCEPROP 3 LASTPIN (-7525 2325) SIG_NAME GND\g
J 0
(-7515 2335);
DISPLAY 0.659574 (-7515 2335);
PAINT MONO (-7515 2335);
DISPLAY INVISIBLE (-7515 2335);
FORCEPROP 2 LAST CDS_LIB pure_quanta_power
J 0
(-7525 2275);
DISPLAY INVISIBLE (-7525 2275);
FORCEPROP 1 LAST HDL_POWER GND
J 1
(-7500 2200);
DISPLAY 0.872340 (-7500 2200);
PAINT GREEN (-7500 2200);
DISPLAY INVISIBLE (-7500 2200);
FORCEPROP 1 LAST PATH I40
J 0
(-7450 2275);
DISPLAY 0.872340 (-7450 2275);
PAINT AQUA (-7450 2275);
DISPLAY INVISIBLE (-7450 2275);
FORCEADD Q_RES..1
(-6800 1500);
FORCEPROP 1 LAST LOCATION PR112
J 0
(-6850 1525);
DISPLAY 0.489362 (-6850 1525);
PAINT SKYBLUE (-6850 1525);
FORCEPROP 0 LAST $SEC 1
J 0
(-6550 1625);
DISPLAY 0.680851 (-6550 1625);
PAINT MONO (-6550 1625);
DISPLAY INVISIBLE (-6550 1625);
FORCEPROP 0 LAST CDS_SEC 1
J 0
(-6550 1625);
DISPLAY 1.021277 (-6550 1625);
DISPLAY INVISIBLE (-6550 1625);
FORCEPROP 1 LASTPIN (-6900 1500) $PN 1
J 0
(-6888 1512);
DISPLAY 0.787234 (-6888 1512);
PAINT MONO (-6888 1512);
DISPLAY INVISIBLE (-6888 1512);
FORCEPROP 1 LASTPIN (-6700 1500) $PN 2
J 0
(-6738 1512);
DISPLAY 0.787234 (-6738 1512);
PAINT MONO (-6738 1512);
DISPLAY INVISIBLE (-6738 1512);
FORCEPROP 1 LAST WATTAGE 1/16W
J 2
(-6550 1575);
DISPLAY 0.489362 (-6550 1575);
PAINT SKYBLUE (-6550 1575);
FORCEPROP 1 LAST MATERIAL CHIP
J 0
(-6650 1525);
DISPLAY 0.489362 (-6650 1525);
PAINT SKYBLUE (-6650 1525);
FORCEPROP 1 LAST TOLERANCE 5%
J 0
(-7000 1525);
DISPLAY 0.489362 (-7000 1525);
PAINT SKYBLUE (-7000 1525);
FORCEPROP 1 LAST VALUE 0
J 2
(-7025 1525);
DISPLAY 0.489362 (-7025 1525);
PAINT SKYBLUE (-7025 1525);
FORCEPROP 1 LAST PACK_TYPE 0402LF
J 0
(-6675 1450);
DISPLAY 0.489362 (-6675 1450);
PAINT SKYBLUE (-6675 1450);
FORCEPROP 2 LAST CDS_LIB pure_quanta
J 0
(-6800 1500);
DISPLAY INVISIBLE (-6800 1500);
FORCEPROP 1 LAST PATH I41
J 0
(-6850 1650);
DISPLAY 0.978723 (-6850 1650);
PAINT WHITE (-6850 1650);
DISPLAY INVISIBLE (-6850 1650);
FORCEPROP 1 LAST PART_NUMBER CS00002JB13
J 0
(-7125 1450);
DISPLAY 0.489362 (-7125 1450);
PAINT SKYBLUE (-7125 1450);
DISPLAY INVISIBLE (-7125 1450);
FORCEADD Q_INDUCTOR4P_14..1
(-6275 2500);
FORCEPROP 1 LAST LOCATION PL20
J 0
(-6550 2675);
DISPLAY 0.489362 (-6550 2675);
PAINT SKYBLUE (-6550 2675);
FORCEPROP 0 LAST $SEC 1
J 0
(-6225 2700);
DISPLAY 0.680851 (-6225 2700);
PAINT MONO (-6225 2700);
DISPLAY INVISIBLE (-6225 2700);
FORCEPROP 0 LAST CDS_SEC 1
J 0
(-6225 2700);
DISPLAY 1.021277 (-6225 2700);
DISPLAY INVISIBLE (-6225 2700);
FORCEPROP 0 LASTPIN (-6675 2625) $PN 1
J 2
(-6685 2635);
DISPLAY 0.489362 (-6685 2635);
PAINT MONO (-6685 2635);
FORCEPROP 0 LASTPIN (-6675 2375) $PN 2
J 2
(-6685 2385);
DISPLAY 0.489362 (-6685 2385);
PAINT MONO (-6685 2385);
FORCEPROP 0 LASTPIN (-5875 2375) $PN 3
J 0
(-5865 2385);
DISPLAY 0.489362 (-5865 2385);
PAINT MONO (-5865 2385);
FORCEPROP 0 LASTPIN (-5875 2625) $PN 4
J 0
(-5865 2635);
DISPLAY 0.489362 (-5865 2635);
PAINT MONO (-5865 2635);
FORCEPROP 2 LAST PART_TYPE SMLF
J 0
(-6350 2250);
DISPLAY 1.021277 (-6350 2250);
FORCEPROP 2 LAST VALUE 150NH
J 0
(-6375 2675);
DISPLAY 0.489362 (-6375 2675);
PAINT SKYBLUE (-6375 2675);
FORCEPROP 1 LAST MATERIAL IND
J 0
(-6475 2675);
DISPLAY 0.489362 (-6475 2675);
PAINT SKYBLUE (-6475 2675);
FORCEPROP 1 LAST NEEDS_NO_SIZE TRUE
J 0
(-6275 2500);
DISPLAY 0.468085 (-6275 2500);
PAINT GREEN (-6275 2500);
DISPLAY INVISIBLE (-6275 2500);
FORCEPROP 2 LAST CDS_LIB pure_quanta
J 0
(-6275 2500);
DISPLAY INVISIBLE (-6275 2500);
FORCEPROP 1 LAST PATH I42
J 0
(-6075 2655);
DISPLAY 0.723404 (-6075 2655);
PAINT GREEN (-6075 2655);
DISPLAY INVISIBLE (-6075 2655);
FORCEPROP 1 LAST PART_NUMBER CV+15^0TZ04
J 0
(-6225 2675);
DISPLAY 0.489362 (-6225 2675);
PAINT SKYBLUE (-6225 2675);
DISPLAY INVISIBLE (-6225 2675);
FORCEADD Q_INDUCTOR..1
R 2
(-7300 2400);
FORCEPROP 1 LAST LOCATION PL16
J 2
(-7400 2575);
DISPLAY 0.574468 (-7400 2575);
PAINT SKYBLUE (-7400 2575);
FORCEPROP 0 LAST $SEC 1
J 0
(-7400 2625);
DISPLAY 0.680851 (-7400 2625);
PAINT MONO (-7400 2625);
DISPLAY INVISIBLE (-7400 2625);
FORCEPROP 0 LAST CDS_SEC 1
J 0
(-7500 2575);
DISPLAY 1.021277 (-7500 2575);
DISPLAY INVISIBLE (-7500 2575);
FORCEPROP 0 LASTPIN (-7200 2375) $PN 1
J 0
(-7190 2385);
DISPLAY 0.680851 (-7190 2385);
PAINT MONO (-7190 2385);
FORCEPROP 0 LASTPIN (-7400 2375) $PN 2
J 2
(-7410 2385);
DISPLAY 0.680851 (-7410 2385);
PAINT MONO (-7410 2385);
FORCEPROP 1 LAST MATERIAL IND
J 2
(-7425 2450);
DISPLAY 0.468085 (-7425 2450);
PAINT SKYBLUE (-7425 2450);
FORCEPROP 2 LAST PACK_TYPE SMLF
J 0
(-7500 2525);
DISPLAY 0.489362 (-7500 2525);
FORCEPROP 2 LAST VALUE 0.22UH/33A
J 0
(-7500 2500);
DISPLAY 0.489362 (-7500 2500);
PAINT SKYBLUE (-7500 2500);
FORCEPROP 2 LAST CDS_LIB pure_quanta
J 0
(-7300 2400);
DISPLAY INVISIBLE (-7300 2400);
FORCEPROP 1 LAST NEEDS_NO_SIZE TRUE
J 2
(-7300 2400);
DISPLAY 0.468085 (-7300 2400);
PAINT GREEN (-7300 2400);
DISPLAY INVISIBLE (-7300 2400);
FORCEPROP 1 LAST PATH I43
J 2
(-7375 2455);
DISPLAY 0.723404 (-7375 2455);
PAINT GREEN (-7375 2455);
DISPLAY INVISIBLE (-7375 2455);
FORCEPROP 1 LAST PART_NUMBER CV+22Y0EZ00
J 2
(-7250 2475);
DISPLAY 0.468085 (-7250 2475);
PAINT SKYBLUE (-7250 2475);
DISPLAY INVISIBLE (-7250 2475);
FORCEADD Q_CAP..1
(-7350 2850);
FORCEPROP 1 LAST LOCATION PC183
J 0
(-7300 2950);
DISPLAY 0.489362 (-7300 2950);
PAINT SKYBLUE (-7300 2950);
FORCEPROP 0 LAST $SEC 1
J 0
(-7300 3000);
DISPLAY 0.680851 (-7300 3000);
PAINT MONO (-7300 3000);
DISPLAY INVISIBLE (-7300 3000);
FORCEPROP 0 LAST CDS_SEC 1
J 2
(-7300 2975);
DISPLAY 1.021277 (-7300 2975);
DISPLAY INVISIBLE (-7300 2975);
FORCEPROP 1 LASTPIN (-7350 2950) $PN 1
J 0
(-7340 2930);
DISPLAY 0.489362 (-7340 2930);
PAINT MONO (-7340 2930);
FORCEPROP 1 LASTPIN (-7350 2750) $PN 2
J 0
(-7340 2730);
DISPLAY 0.489362 (-7340 2730);
PAINT MONO (-7340 2730);
FORCEPROP 1 LAST PACK_TYPE 0402
J 0
(-7300 2650);
DISPLAY 0.489362 (-7300 2650);
PAINT SKYBLUE (-7300 2650);
FORCEPROP 1 LAST VOLTAGE 16V
J 0
(-7300 2850);
DISPLAY 0.489362 (-7300 2850);
PAINT SKYBLUE (-7300 2850);
FORCEPROP 1 LAST VALUE 0.22UF
J 0
(-7300 2900);
DISPLAY 0.489362 (-7300 2900);
PAINT SKYBLUE (-7300 2900);
FORCEPROP 1 LAST TOLERANCE 10%
J 0
(-7300 2800);
DISPLAY 0.489362 (-7300 2800);
PAINT SKYBLUE (-7300 2800);
FORCEPROP 1 LAST MATERIAL X7R
J 0
(-7300 2750);
DISPLAY 0.489362 (-7300 2750);
PAINT SKYBLUE (-7300 2750);
FORCEPROP 2 LAST CDS_LIB pure_quanta
J 2
(-7350 2850);
DISPLAY INVISIBLE (-7350 2850);
FORCEPROP 1 LAST PATH I44
J 0
(-7300 3000);
DISPLAY 0.978723 (-7300 3000);
PAINT WHITE (-7300 3000);
DISPLAY INVISIBLE (-7300 3000);
FORCEPROP 1 LAST PART_NUMBER CH4223K1B00
J 0
(-7300 2700);
DISPLAY 0.489362 (-7300 2700);
PAINT SKYBLUE (-7300 2700);
DISPLAY INVISIBLE (-7300 2700);
FORCEADD Q_CAP..1
(-8000 3575);
FORCEPROP 1 LAST LOCATION PC180_4
J 0
(-7950 3725);
DISPLAY 0.489362 (-7950 3725);
PAINT SKYBLUE (-7950 3725);
FORCEPROP 0 LAST $SEC 1
J 0
(-7950 3775);
DISPLAY 0.680851 (-7950 3775);
PAINT MONO (-7950 3775);
DISPLAY INVISIBLE (-7950 3775);
FORCEPROP 0 LAST CDS_SEC 1
J 0
(-7950 3775);
DISPLAY 1.021277 (-7950 3775);
DISPLAY INVISIBLE (-7950 3775);
FORCEPROP 1 LASTPIN (-8000 3675) $PN 1
J 0
(-7990 3655);
DISPLAY 0.489362 (-7990 3655);
PAINT MONO (-7990 3655);
FORCEPROP 1 LASTPIN (-8000 3475) $PN 2
J 0
(-7990 3455);
DISPLAY 0.489362 (-7990 3455);
PAINT MONO (-7990 3455);
FORCEPROP 1 LAST PACK_TYPE C0402
J 0
(-7950 3475);
DISPLAY 0.489362 (-7950 3475);
PAINT SKYBLUE (-7950 3475);
FORCEPROP 1 LAST VOLTAGE 25V
J 0
(-7950 3625);
DISPLAY 0.489362 (-7950 3625);
PAINT SKYBLUE (-7950 3625);
FORCEPROP 1 LAST VALUE 1UF
J 0
(-7950 3675);
DISPLAY 0.489362 (-7950 3675);
PAINT SKYBLUE (-7950 3675);
FORCEPROP 1 LAST TOLERANCE 10%
J 0
(-7950 3575);
DISPLAY 0.489362 (-7950 3575);
PAINT SKYBLUE (-7950 3575);
FORCEPROP 1 LAST MATERIAL X6S
J 0
(-7950 3525);
DISPLAY 0.489362 (-7950 3525);
PAINT SKYBLUE (-7950 3525);
FORCEPROP 2 LAST CDS_LIB pure_quanta
J 0
(-8000 3575);
DISPLAY INVISIBLE (-8000 3575);
FORCEPROP 1 LAST PATH I45
J 0
(-7950 3725);
DISPLAY 0.978723 (-7950 3725);
PAINT WHITE (-7950 3725);
DISPLAY INVISIBLE (-7950 3725);
FORCEPROP 1 LAST PART_NUMBER CH5104KEB02
J 0
(-7950 3425);
DISPLAY 0.489362 (-7950 3425);
PAINT SKYBLUE (-7950 3425);
DISPLAY INVISIBLE (-7950 3425);
FORCEADD Q_CAP..1
(-7600 3575);
FORCEPROP 1 LAST LOCATION PC182_4
J 0
(-7550 3725);
DISPLAY 0.489362 (-7550 3725);
PAINT SKYBLUE (-7550 3725);
FORCEPROP 0 LAST $SEC 1
J 0
(-7550 3775);
DISPLAY 0.680851 (-7550 3775);
PAINT MONO (-7550 3775);
DISPLAY INVISIBLE (-7550 3775);
FORCEPROP 0 LAST CDS_SEC 1
J 0
(-7550 3775);
DISPLAY 1.021277 (-7550 3775);
DISPLAY INVISIBLE (-7550 3775);
FORCEPROP 1 LASTPIN (-7600 3675) $PN 1
J 0
(-7590 3655);
DISPLAY 0.489362 (-7590 3655);
PAINT MONO (-7590 3655);
FORCEPROP 1 LASTPIN (-7600 3475) $PN 2
J 0
(-7590 3455);
DISPLAY 0.489362 (-7590 3455);
PAINT MONO (-7590 3455);
FORCEPROP 1 LAST TOLERANCE 20%
J 0
(-7550 3575);
DISPLAY 0.489362 (-7550 3575);
PAINT SKYBLUE (-7550 3575);
FORCEPROP 1 LAST VOLTAGE 16V
J 0
(-7550 3625);
DISPLAY 0.489362 (-7550 3625);
PAINT SKYBLUE (-7550 3625);
FORCEPROP 1 LAST VALUE 22UF
J 0
(-7550 3675);
DISPLAY 0.489362 (-7550 3675);
PAINT SKYBLUE (-7550 3675);
FORCEPROP 1 LAST MATERIAL X6S
J 0
(-7550 3525);
DISPLAY 0.489362 (-7550 3525);
PAINT SKYBLUE (-7550 3525);
FORCEPROP 1 LAST PACK_TYPE C0805
J 0
(-7550 3475);
DISPLAY 0.489362 (-7550 3475);
PAINT SKYBLUE (-7550 3475);
FORCEPROP 2 LAST CDS_LIB pure_quanta
J 0
(-7600 3575);
DISPLAY INVISIBLE (-7600 3575);
FORCEPROP 1 LAST PATH I46
J 0
(-7550 3725);
DISPLAY 0.978723 (-7550 3725);
PAINT WHITE (-7550 3725);
DISPLAY INVISIBLE (-7550 3725);
FORCEPROP 1 LAST PART_NUMBER CH6223MEA01
J 0
(-7550 3425);
DISPLAY 0.489362 (-7550 3425);
PAINT SKYBLUE (-7550 3425);
DISPLAY INVISIBLE (-7550 3425);
FORCEADD Q_CAP..1
(-7200 3575);
FORCEPROP 1 LAST LOCATION PC185_4
J 0
(-7150 3725);
DISPLAY 0.489362 (-7150 3725);
PAINT SKYBLUE (-7150 3725);
FORCEPROP 0 LAST $SEC 1
J 0
(-7150 3775);
DISPLAY 0.680851 (-7150 3775);
PAINT MONO (-7150 3775);
DISPLAY INVISIBLE (-7150 3775);
FORCEPROP 0 LAST CDS_SEC 1
J 0
(-7150 3775);
DISPLAY 1.021277 (-7150 3775);
DISPLAY INVISIBLE (-7150 3775);
FORCEPROP 1 LASTPIN (-7200 3675) $PN 1
J 0
(-7190 3655);
DISPLAY 0.489362 (-7190 3655);
PAINT MONO (-7190 3655);
FORCEPROP 1 LASTPIN (-7200 3475) $PN 2
J 0
(-7190 3455);
DISPLAY 0.489362 (-7190 3455);
PAINT MONO (-7190 3455);
FORCEPROP 1 LAST TOLERANCE 20%
J 0
(-7150 3575);
DISPLAY 0.489362 (-7150 3575);
PAINT SKYBLUE (-7150 3575);
FORCEPROP 1 LAST VOLTAGE 16V
J 0
(-7150 3625);
DISPLAY 0.489362 (-7150 3625);
PAINT SKYBLUE (-7150 3625);
FORCEPROP 1 LAST VALUE 22UF
J 0
(-7150 3675);
DISPLAY 0.489362 (-7150 3675);
PAINT SKYBLUE (-7150 3675);
FORCEPROP 1 LAST MATERIAL X6S
J 0
(-7150 3525);
DISPLAY 0.489362 (-7150 3525);
PAINT SKYBLUE (-7150 3525);
FORCEPROP 1 LAST PACK_TYPE C0805
J 0
(-7150 3475);
DISPLAY 0.489362 (-7150 3475);
PAINT SKYBLUE (-7150 3475);
FORCEPROP 2 LAST CDS_LIB pure_quanta
J 0
(-7200 3575);
DISPLAY INVISIBLE (-7200 3575);
FORCEPROP 1 LAST PATH I47
J 0
(-7150 3725);
DISPLAY 0.978723 (-7150 3725);
PAINT WHITE (-7150 3725);
DISPLAY INVISIBLE (-7150 3725);
FORCEPROP 1 LAST PART_NUMBER CH6223MEA01
J 0
(-7150 3425);
DISPLAY 0.489362 (-7150 3425);
PAINT SKYBLUE (-7150 3425);
DISPLAY INVISIBLE (-7150 3425);
FORCEADD UNIVERSAL_GND..1
(-6725 3200);
FORCEPROP 3 LASTPIN (-6725 3250) SIG_NAME GND\g
J 0
(-6715 3260);
DISPLAY 0.659574 (-6715 3260);
PAINT MONO (-6715 3260);
DISPLAY INVISIBLE (-6715 3260);
FORCEPROP 2 LAST CDS_LIB pure_quanta_power
J 0
(-6725 3200);
PAINT MONO (-6725 3200);
DISPLAY INVISIBLE (-6725 3200);
FORCEPROP 1 LAST HDL_POWER GND
J 1
(-6700 3125);
DISPLAY 0.872340 (-6700 3125);
PAINT GREEN (-6700 3125);
DISPLAY INVISIBLE (-6700 3125);
FORCEPROP 1 LAST PATH I48
J 0
(-6650 3200);
DISPLAY 0.872340 (-6650 3200);
PAINT AQUA (-6650 3200);
DISPLAY INVISIBLE (-6650 3200);
FORCEADD Q_CAP..1
(-6725 3575);
FORCEPROP 1 LAST LOCATION PC188_4
J 0
(-6675 3675);
DISPLAY 0.489362 (-6675 3675);
PAINT SKYBLUE (-6675 3675);
FORCEPROP 0 LAST $SEC 1
J 0
(-6675 3725);
DISPLAY 0.680851 (-6675 3725);
PAINT MONO (-6675 3725);
DISPLAY INVISIBLE (-6675 3725);
FORCEPROP 0 LAST CDS_SEC 1
J 0
(-6675 3725);
DISPLAY 1.021277 (-6675 3725);
DISPLAY INVISIBLE (-6675 3725);
FORCEPROP 1 LASTPIN (-6725 3675) $PN 1
J 0
(-6715 3655);
DISPLAY 0.489362 (-6715 3655);
PAINT MONO (-6715 3655);
FORCEPROP 1 LASTPIN (-6725 3475) $PN 2
J 0
(-6715 3455);
DISPLAY 0.489362 (-6715 3455);
PAINT MONO (-6715 3455);
FORCEPROP 1 LAST TOLERANCE 20%
J 0
(-6675 3525);
DISPLAY 0.489362 (-6675 3525);
PAINT SKYBLUE (-6675 3525);
FORCEPROP 1 LAST VOLTAGE 16V
J 0
(-6675 3575);
DISPLAY 0.489362 (-6675 3575);
PAINT SKYBLUE (-6675 3575);
FORCEPROP 1 LAST VALUE 22UF
J 0
(-6675 3625);
DISPLAY 0.489362 (-6675 3625);
PAINT SKYBLUE (-6675 3625);
FORCEPROP 1 LAST MATERIAL X6S
J 0
(-6675 3475);
DISPLAY 0.489362 (-6675 3475);
PAINT SKYBLUE (-6675 3475);
FORCEPROP 1 LAST PACK_TYPE C0805
J 0
(-6675 3375);
DISPLAY 0.489362 (-6675 3375);
PAINT SKYBLUE (-6675 3375);
FORCEPROP 2 LAST CDS_LIB pure_quanta
J 0
(-6725 3575);
DISPLAY INVISIBLE (-6725 3575);
FORCEPROP 1 LAST PATH I49
J 0
(-6675 3725);
DISPLAY 0.978723 (-6675 3725);
PAINT WHITE (-6675 3725);
DISPLAY INVISIBLE (-6675 3725);
FORCEPROP 1 LAST PART_NUMBER CH6223MEA01
J 0
(-6675 3425);
DISPLAY 0.489362 (-6675 3425);
PAINT SKYBLUE (-6675 3425);
DISPLAY INVISIBLE (-6675 3425);
FORCEADD OFFPAGE..1
(-10900 2025);
FORCEPROP 2 LAST $XR0 200 
J 0
(-11182 2025);
DISPLAY 0.638298 (-11182 2025);
PAINT MONO (-11182 2025);
FORCEPROP 2 LAST CDS_LIB standard
J 0
(-10900 2025);
DISPLAY INVISIBLE (-10900 2025);
FORCEPROP 1 LAST OFFPAGE TRUE
J 0
(-10575 1900);
DISPLAY 0.872340 (-10575 1900);
PAINT GREEN (-10575 1900);
DISPLAY INVISIBLE (-10575 1900);
FORCEPROP 1 LAST COMMENT_BODY TRUE
J 0
(-10775 1925);
DISPLAY 0.872340 (-10775 1925);
PAINT GREEN (-10775 1925);
DISPLAY INVISIBLE (-10775 1925);
FORCEPROP 2 LAST PATH I5
J 0
(-11150 2075);
DISPLAY 0.680851 (-11150 2075);
DISPLAY INVISIBLE (-11150 2075);
FORCEADD Q_RES..1
(-6700 4300);
FORCEPROP 1 LAST LOCATION PR111
J 0
(-6750 4325);
DISPLAY 0.489362 (-6750 4325);
PAINT SKYBLUE (-6750 4325);
FORCEPROP 0 LAST $SEC 1
J 0
(-6825 4475);
DISPLAY 0.680851 (-6825 4475);
PAINT MONO (-6825 4475);
DISPLAY INVISIBLE (-6825 4475);
FORCEPROP 0 LAST CDS_SEC 1
J 0
(-6825 4475);
DISPLAY 1.021277 (-6825 4475);
DISPLAY INVISIBLE (-6825 4475);
FORCEPROP 1 LASTPIN (-6800 4300) $PN 1
J 0
(-6788 4312);
DISPLAY 0.787234 (-6788 4312);
PAINT MONO (-6788 4312);
DISPLAY INVISIBLE (-6788 4312);
FORCEPROP 1 LASTPIN (-6600 4300) $PN 2
J 0
(-6638 4312);
DISPLAY 0.787234 (-6638 4312);
PAINT MONO (-6638 4312);
DISPLAY INVISIBLE (-6638 4312);
FORCEPROP 1 LAST WATTAGE 1/16W
J 2
(-6475 4375);
DISPLAY 0.489362 (-6475 4375);
PAINT SKYBLUE (-6475 4375);
FORCEPROP 1 LAST MATERIAL CHIP
J 0
(-6575 4325);
DISPLAY 0.489362 (-6575 4325);
PAINT SKYBLUE (-6575 4325);
FORCEPROP 1 LAST VALUE 0
J 2
(-6900 4325);
DISPLAY 0.489362 (-6900 4325);
PAINT SKYBLUE (-6900 4325);
FORCEPROP 1 LAST PACK_TYPE 0402LF
J 0
(-6625 4250);
DISPLAY 0.489362 (-6625 4250);
PAINT SKYBLUE (-6625 4250);
FORCEPROP 1 LAST TOLERANCE 5%
J 0
(-6875 4325);
DISPLAY 0.489362 (-6875 4325);
PAINT SKYBLUE (-6875 4325);
FORCEPROP 2 LAST CDS_LIB pure_quanta
J 0
(-6700 4300);
DISPLAY INVISIBLE (-6700 4300);
FORCEPROP 1 LAST PATH I50
J 0
(-6750 4450);
DISPLAY 0.978723 (-6750 4450);
PAINT WHITE (-6750 4450);
DISPLAY INVISIBLE (-6750 4450);
FORCEPROP 1 LAST PART_NUMBER CS00002JB13
J 0
(-7000 4250);
DISPLAY 0.489362 (-7000 4250);
PAINT SKYBLUE (-7000 4250);
DISPLAY INVISIBLE (-7000 4250);
FORCEADD VCC_CORE..1
(-6725 3950);
FORCEPROP 3 LASTPIN (-6725 3900) SIG_NAME SW_P12V_AUX_PVDDIO_P0_FLT\g
J 0
(-6715 3910);
DISPLAY 0.659574 (-6715 3910);
PAINT MONO (-6715 3910);
DISPLAY INVISIBLE (-6715 3910);
FORCEPROP 1 LAST HDL_POWER SW_P12V_AUX_PVDDIO_P0_FLT
J 1
(-6725 4000);
DISPLAY 0.489362 (-6725 4000);
PAINT GREEN (-6725 4000);
FORCEPROP 2 LAST CDS_LIB pure_quanta_power
J 0
(-6725 3950);
DISPLAY INVISIBLE (-6725 3950);
FORCEPROP 1 LAST PATH I51
J 0
(-6675 3975);
DISPLAY 0.872340 (-6675 3975);
PAINT AQUA (-6675 3975);
DISPLAY INVISIBLE (-6675 3975);
FORCEADD OFFPAGE..3
(-5275 2375);
FORCEPROP 2 LAST $XR0 206 
J 0
(-5061 2375);
DISPLAY 0.638298 (-5061 2375);
PAINT MONO (-5061 2375);
FORCEPROP 2 LAST CDS_LIB standard
J 0
(-5275 2375);
DISPLAY INVISIBLE (-5275 2375);
FORCEPROP 1 LAST OFFPAGE TRUE
J 0
(-4950 2250);
DISPLAY 0.872340 (-4950 2250);
PAINT GREEN (-4950 2250);
DISPLAY INVISIBLE (-4950 2250);
FORCEPROP 1 LAST COMMENT_BODY TRUE
J 0
(-5325 2275);
DISPLAY 0.872340 (-5325 2275);
PAINT GREEN (-5325 2275);
DISPLAY INVISIBLE (-5325 2275);
FORCEPROP 2 LAST PATH I52
J 0
(-5050 2425);
DISPLAY 0.680851 (-5050 2425);
DISPLAY INVISIBLE (-5050 2425);
FORCEADD Q_CAP..1
(-4200 2425);
FORCEPROP 1 LAST LOCATION PC189_4
J 0
(-4150 2550);
DISPLAY 0.489362 (-4150 2550);
PAINT SKYBLUE (-4150 2550);
FORCEPROP 0 LAST $SEC 1
J 0
(-4150 2600);
DISPLAY 0.680851 (-4150 2600);
PAINT MONO (-4150 2600);
DISPLAY INVISIBLE (-4150 2600);
FORCEPROP 0 LAST CDS_SEC 1
J 0
(-4150 2600);
DISPLAY 1.021277 (-4150 2600);
DISPLAY INVISIBLE (-4150 2600);
FORCEPROP 1 LASTPIN (-4200 2525) $PN 1
J 0
(-4190 2505);
DISPLAY 0.489362 (-4190 2505);
PAINT MONO (-4190 2505);
FORCEPROP 1 LASTPIN (-4200 2325) $PN 2
J 0
(-4190 2305);
DISPLAY 0.489362 (-4190 2305);
PAINT MONO (-4190 2305);
FORCEPROP 1 LAST PACK_TYPE C0805
J 0
(-4150 2300);
DISPLAY 0.489362 (-4150 2300);
PAINT SKYBLUE (-4150 2300);
FORCEPROP 1 LAST MATERIAL X6S
J 0
(-4150 2350);
DISPLAY 0.489362 (-4150 2350);
PAINT SKYBLUE (-4150 2350);
FORCEPROP 1 LAST TOLERANCE 20%
J 0
(-4150 2400);
DISPLAY 0.489362 (-4150 2400);
PAINT SKYBLUE (-4150 2400);
FORCEPROP 1 LAST VALUE 22UF
J 0
(-4150 2500);
DISPLAY 0.489362 (-4150 2500);
PAINT SKYBLUE (-4150 2500);
FORCEPROP 1 LAST VOLTAGE 4V
J 0
(-4150 2450);
DISPLAY 0.489362 (-4150 2450);
PAINT SKYBLUE (-4150 2450);
FORCEPROP 2 LAST CDS_LIB pure_quanta
J 0
(-4200 2425);
DISPLAY INVISIBLE (-4200 2425);
FORCEPROP 1 LAST PATH I53
J 0
(-4150 2575);
DISPLAY 0.978723 (-4150 2575);
PAINT WHITE (-4150 2575);
DISPLAY INVISIBLE (-4150 2575);
FORCEPROP 1 LAST PART_NUMBER CH622KMEA03
J 0
(-4150 2250);
DISPLAY 0.489362 (-4150 2250);
PAINT SKYBLUE (-4150 2250);
DISPLAY INVISIBLE (-4150 2250);
FORCEADD UNIVERSAL_GND..1
(-7950 4475);
FORCEPROP 3 LASTPIN (-7950 4525) SIG_NAME GND\g
J 0
(-7940 4535);
DISPLAY 0.659574 (-7940 4535);
PAINT MONO (-7940 4535);
DISPLAY INVISIBLE (-7940 4535);
FORCEPROP 2 LAST CDS_LIB pure_quanta_power
J 0
(-7950 4475);
DISPLAY INVISIBLE (-7950 4475);
FORCEPROP 1 LAST HDL_POWER GND
J 1
(-7925 4400);
DISPLAY 0.872340 (-7925 4400);
PAINT GREEN (-7925 4400);
DISPLAY INVISIBLE (-7925 4400);
FORCEPROP 1 LAST PATH I54
J 0
(-7875 4475);
DISPLAY 0.872340 (-7875 4475);
PAINT AQUA (-7875 4475);
DISPLAY INVISIBLE (-7875 4475);
FORCEADD Q_RES..2
(-7950 4700);
FORCEPROP 1 LAST LOCATION PR379
J 0
(-7905 4825);
DISPLAY 0.489362 (-7905 4825);
PAINT SKYBLUE (-7905 4825);
FORCEPROP 0 LAST $SEC 1
J 0
(-7900 4875);
DISPLAY 0.680851 (-7900 4875);
PAINT MONO (-7900 4875);
DISPLAY INVISIBLE (-7900 4875);
FORCEPROP 0 LAST CDS_SEC 1
J 0
(-7900 4875);
DISPLAY 1.021277 (-7900 4875);
DISPLAY INVISIBLE (-7900 4875);
FORCEPROP 1 LASTPIN (-7950 4800) $PN 1
J 0
(-7945 4762);
DISPLAY 0.489362 (-7945 4762);
PAINT MONO (-7945 4762);
FORCEPROP 1 LASTPIN (-7950 4600) $PN 2
J 0
(-7945 4610);
DISPLAY 0.489362 (-7945 4610);
PAINT MONO (-7945 4610);
FORCEPROP 1 LAST PACK_TYPE 0402LF
J 0
(-7910 4525);
DISPLAY 0.489362 (-7910 4525);
PAINT SKYBLUE (-7910 4525);
FORCEPROP 1 LAST TOLERANCE 1%
J 0
(-7905 4725);
DISPLAY 0.489362 (-7905 4725);
PAINT SKYBLUE (-7905 4725);
FORCEPROP 1 LAST WATTAGE 1/8W
J 0
(-7910 4675);
DISPLAY 0.489362 (-7910 4675);
PAINT SKYBLUE (-7910 4675);
FORCEPROP 1 LAST VALUE 1.5
J 0
(-7905 4775);
DISPLAY 0.489362 (-7905 4775);
PAINT SKYBLUE (-7905 4775);
FORCEPROP 1 LAST MATERIAL EMPTY
J 0
(-7910 4625);
DISPLAY 0.489362 (-7910 4625);
PAINT RED (-7910 4625);
FORCEPROP 2 LAST CDS_LIB pure_quanta
J 0
(-7950 4700);
DISPLAY INVISIBLE (-7950 4700);
FORCEPROP 1 LAST PATH I55
J 0
(-7900 4875);
DISPLAY 0.978723 (-7900 4875);
PAINT WHITE (-7900 4875);
DISPLAY INVISIBLE (-7900 4875);
FORCEPROP 1 LAST PART_NUMBER CS-1504FB00
J 0
(-7910 4575);
DISPLAY 0.489362 (-7910 4575);
PAINT SKYBLUE (-7910 4575);
DISPLAY INVISIBLE (-7910 4575);
FORCEADD Q_CAP..1
(-7950 5225);
FORCEPROP 1 LAST LOCATION PC166
J 0
(-7900 5325);
DISPLAY 0.489362 (-7900 5325);
PAINT SKYBLUE (-7900 5325);
FORCEPROP 0 LAST $SEC 1
J 0
(-7900 5375);
DISPLAY 0.680851 (-7900 5375);
PAINT MONO (-7900 5375);
DISPLAY INVISIBLE (-7900 5375);
FORCEPROP 0 LAST CDS_SEC 1
J 0
(-7900 5375);
DISPLAY 1.021277 (-7900 5375);
DISPLAY INVISIBLE (-7900 5375);
FORCEPROP 1 LASTPIN (-7950 5325) $PN 1
J 0
(-7940 5305);
DISPLAY 0.489362 (-7940 5305);
PAINT MONO (-7940 5305);
FORCEPROP 1 LASTPIN (-7950 5125) $PN 2
J 0
(-7940 5105);
DISPLAY 0.489362 (-7940 5105);
PAINT MONO (-7940 5105);
FORCEPROP 1 LAST MATERIAL EMPTY
J 0
(-7900 5125);
DISPLAY 0.489362 (-7900 5125);
PAINT RED (-7900 5125);
FORCEPROP 1 LAST TOLERANCE 10%
J 0
(-7900 5175);
DISPLAY 0.489362 (-7900 5175);
PAINT SKYBLUE (-7900 5175);
FORCEPROP 1 LAST VALUE 560PF
J 0
(-7900 5275);
DISPLAY 0.489362 (-7900 5275);
PAINT SKYBLUE (-7900 5275);
FORCEPROP 1 LAST PACK_TYPE C0402
J 0
(-7900 5025);
DISPLAY 0.489362 (-7900 5025);
PAINT SKYBLUE (-7900 5025);
FORCEPROP 1 LAST VOLTAGE 50V
J 0
(-7900 5225);
DISPLAY 0.489362 (-7900 5225);
PAINT SKYBLUE (-7900 5225);
FORCEPROP 2 LAST CDS_LIB pure_quanta
J 0
(-7950 5225);
DISPLAY INVISIBLE (-7950 5225);
FORCEPROP 1 LAST PATH I56
J 0
(-7900 5375);
DISPLAY 0.978723 (-7900 5375);
PAINT WHITE (-7900 5375);
DISPLAY INVISIBLE (-7900 5375);
FORCEPROP 1 LAST PART_NUMBER CH1566K1B09
J 0
(-7900 5075);
DISPLAY 0.489362 (-7900 5075);
PAINT SKYBLUE (-7900 5075);
DISPLAY INVISIBLE (-7900 5075);
FORCEADD OFFPAGE..6
(-7150 5175);
FORCEPROP 2 LAST $XR0 206 
J 0
(-7430 5175);
DISPLAY 0.638298 (-7430 5175);
PAINT MONO (-7430 5175);
FORCEPROP 2 LAST CDS_LIB standard
J 0
(-7150 5175);
DISPLAY INVISIBLE (-7150 5175);
FORCEPROP 1 LAST OFFPAGE TRUE
J 0
(-6825 5050);
DISPLAY 0.872340 (-6825 5050);
PAINT GREEN (-6825 5050);
DISPLAY INVISIBLE (-6825 5050);
FORCEPROP 1 LAST COMMENT_BODY TRUE
J 0
(-7050 5100);
DISPLAY 0.872340 (-7050 5100);
PAINT GREEN (-7050 5100);
DISPLAY INVISIBLE (-7050 5100);
FORCEPROP 2 LAST PATH I57
J 0
(-7450 5225);
DISPLAY 0.680851 (-7450 5225);
DISPLAY INVISIBLE (-7450 5225);
FORCEADD Q_CAP..1
(-7675 6375);
FORCEPROP 1 LAST LOCATION PC181_3
J 0
(-7625 6525);
DISPLAY 0.489362 (-7625 6525);
PAINT SKYBLUE (-7625 6525);
FORCEPROP 0 LAST $SEC 1
J 0
(-7625 6575);
DISPLAY 0.680851 (-7625 6575);
PAINT MONO (-7625 6575);
DISPLAY INVISIBLE (-7625 6575);
FORCEPROP 0 LAST CDS_SEC 1
J 0
(-7625 6575);
DISPLAY 1.021277 (-7625 6575);
DISPLAY INVISIBLE (-7625 6575);
FORCEPROP 1 LASTPIN (-7675 6475) $PN 1
J 0
(-7665 6455);
DISPLAY 0.489362 (-7665 6455);
PAINT MONO (-7665 6455);
FORCEPROP 1 LASTPIN (-7675 6275) $PN 2
J 0
(-7665 6255);
DISPLAY 0.489362 (-7665 6255);
PAINT MONO (-7665 6255);
FORCEPROP 1 LAST TOLERANCE 20%
J 0
(-7625 6375);
DISPLAY 0.489362 (-7625 6375);
PAINT SKYBLUE (-7625 6375);
FORCEPROP 1 LAST VOLTAGE 16V
J 0
(-7625 6425);
DISPLAY 0.489362 (-7625 6425);
PAINT SKYBLUE (-7625 6425);
FORCEPROP 1 LAST VALUE 22UF
J 0
(-7625 6475);
DISPLAY 0.489362 (-7625 6475);
PAINT SKYBLUE (-7625 6475);
FORCEPROP 1 LAST MATERIAL X6S
J 0
(-7625 6325);
DISPLAY 0.489362 (-7625 6325);
PAINT SKYBLUE (-7625 6325);
FORCEPROP 1 LAST PACK_TYPE C0805
J 0
(-7625 6275);
DISPLAY 0.489362 (-7625 6275);
PAINT SKYBLUE (-7625 6275);
FORCEPROP 2 LAST CDS_LIB pure_quanta
J 0
(-7675 6375);
DISPLAY INVISIBLE (-7675 6375);
FORCEPROP 1 LAST PATH I58
J 0
(-7625 6525);
DISPLAY 0.978723 (-7625 6525);
PAINT WHITE (-7625 6525);
DISPLAY INVISIBLE (-7625 6525);
FORCEPROP 1 LAST PART_NUMBER CH6223MEA01
J 0
(-7625 6225);
DISPLAY 0.489362 (-7625 6225);
PAINT SKYBLUE (-7625 6225);
DISPLAY INVISIBLE (-7625 6225);
FORCEADD Q_CAP..1
(-7050 5650);
FORCEPROP 1 LAST LOCATION PC186
J 0
(-7000 5750);
DISPLAY 0.489362 (-7000 5750);
PAINT SKYBLUE (-7000 5750);
FORCEPROP 0 LAST $SEC 1
J 0
(-7000 5800);
DISPLAY 0.680851 (-7000 5800);
PAINT MONO (-7000 5800);
DISPLAY INVISIBLE (-7000 5800);
FORCEPROP 0 LAST CDS_SEC 1
J 0
(-7000 5800);
DISPLAY 1.021277 (-7000 5800);
DISPLAY INVISIBLE (-7000 5800);
FORCEPROP 1 LASTPIN (-7050 5750) $PN 1
J 0
(-7040 5730);
DISPLAY 0.489362 (-7040 5730);
PAINT MONO (-7040 5730);
FORCEPROP 1 LASTPIN (-7050 5550) $PN 2
J 0
(-7040 5530);
DISPLAY 0.489362 (-7040 5530);
PAINT MONO (-7040 5530);
FORCEPROP 1 LAST TOLERANCE 10%
J 0
(-7000 5600);
DISPLAY 0.489362 (-7000 5600);
PAINT SKYBLUE (-7000 5600);
FORCEPROP 1 LAST PACK_TYPE 0402
J 0
(-7000 5450);
DISPLAY 0.489362 (-7000 5450);
PAINT SKYBLUE (-7000 5450);
FORCEPROP 1 LAST VALUE 0.22UF
J 0
(-7000 5700);
DISPLAY 0.489362 (-7000 5700);
PAINT SKYBLUE (-7000 5700);
FORCEPROP 1 LAST MATERIAL X7R
J 0
(-7000 5550);
DISPLAY 0.489362 (-7000 5550);
PAINT SKYBLUE (-7000 5550);
FORCEPROP 1 LAST VOLTAGE 16V
J 0
(-7000 5650);
DISPLAY 0.489362 (-7000 5650);
PAINT SKYBLUE (-7000 5650);
FORCEPROP 2 LAST CDS_LIB pure_quanta
J 0
(-7050 5650);
PAINT MONO (-7050 5650);
DISPLAY INVISIBLE (-7050 5650);
FORCEPROP 1 LAST PATH I59
J 0
(-7000 5800);
DISPLAY 0.978723 (-7000 5800);
PAINT WHITE (-7000 5800);
DISPLAY INVISIBLE (-7000 5800);
FORCEPROP 1 LAST PART_NUMBER CH4223K1B00
J 0
(-7000 5500);
DISPLAY 0.489362 (-7000 5500);
PAINT SKYBLUE (-7000 5500);
DISPLAY INVISIBLE (-7000 5500);
FORCEADD OFFPAGE..5
(-10900 2125);
FORCEPROP 2 LAST $XR2 200 
J 0
(-11155 2161);
DISPLAY 0.638298 (-11155 2161);
PAINT MONO (-11155 2161);
FORCEPROP 2 LAST $XR1 206 
J 0
(-11155 2089);
DISPLAY 0.638298 (-11155 2089);
PAINT MONO (-11155 2089);
FORCEPROP 2 LAST $XR0 205 
J 0
(-11155 2125);
DISPLAY 0.638298 (-11155 2125);
PAINT MONO (-11155 2125);
FORCEPROP 2 LAST CDS_LIB standard
J 0
(-10900 2125);
DISPLAY INVISIBLE (-10900 2125);
FORCEPROP 1 LAST OFFPAGE TRUE
J 0
(-10575 2000);
DISPLAY 0.872340 (-10575 2000);
PAINT GREEN (-10575 2000);
DISPLAY INVISIBLE (-10575 2000);
FORCEPROP 1 LAST COMMENT_BODY TRUE
J 0
(-10800 2050);
DISPLAY 0.872340 (-10800 2050);
PAINT GREEN (-10800 2050);
DISPLAY INVISIBLE (-10800 2050);
FORCEPROP 2 LAST PATH I6
J 0
(-11175 2200);
DISPLAY 0.680851 (-11175 2200);
DISPLAY INVISIBLE (-11175 2200);
FORCEADD Q_CAP..1
(-7275 6375);
FORCEPROP 1 LAST LOCATION PC184_3
J 0
(-7225 6525);
DISPLAY 0.489362 (-7225 6525);
PAINT SKYBLUE (-7225 6525);
FORCEPROP 0 LAST $SEC 1
J 0
(-7225 6575);
DISPLAY 0.680851 (-7225 6575);
PAINT MONO (-7225 6575);
DISPLAY INVISIBLE (-7225 6575);
FORCEPROP 0 LAST CDS_SEC 1
J 0
(-7225 6575);
DISPLAY 1.021277 (-7225 6575);
DISPLAY INVISIBLE (-7225 6575);
FORCEPROP 1 LASTPIN (-7275 6475) $PN 1
J 0
(-7265 6455);
DISPLAY 0.489362 (-7265 6455);
PAINT MONO (-7265 6455);
FORCEPROP 1 LASTPIN (-7275 6275) $PN 2
J 0
(-7265 6255);
DISPLAY 0.489362 (-7265 6255);
PAINT MONO (-7265 6255);
FORCEPROP 1 LAST TOLERANCE 20%
J 0
(-7225 6375);
DISPLAY 0.489362 (-7225 6375);
PAINT SKYBLUE (-7225 6375);
FORCEPROP 1 LAST VOLTAGE 16V
J 0
(-7225 6425);
DISPLAY 0.489362 (-7225 6425);
PAINT SKYBLUE (-7225 6425);
FORCEPROP 1 LAST VALUE 22UF
J 0
(-7225 6475);
DISPLAY 0.489362 (-7225 6475);
PAINT SKYBLUE (-7225 6475);
FORCEPROP 1 LAST MATERIAL X6S
J 0
(-7225 6325);
DISPLAY 0.489362 (-7225 6325);
PAINT SKYBLUE (-7225 6325);
FORCEPROP 1 LAST PACK_TYPE C0805
J 0
(-7225 6275);
DISPLAY 0.489362 (-7225 6275);
PAINT SKYBLUE (-7225 6275);
FORCEPROP 2 LAST CDS_LIB pure_quanta
J 0
(-7275 6375);
DISPLAY INVISIBLE (-7275 6375);
FORCEPROP 1 LAST PATH I60
J 0
(-7225 6525);
DISPLAY 0.978723 (-7225 6525);
PAINT WHITE (-7225 6525);
DISPLAY INVISIBLE (-7225 6525);
FORCEPROP 1 LAST PART_NUMBER CH6223MEA01
J 0
(-7225 6225);
DISPLAY 0.489362 (-7225 6225);
PAINT SKYBLUE (-7225 6225);
DISPLAY INVISIBLE (-7225 6225);
FORCEADD Q_INDUCTOR4P_14..1
(-6025 5300);
FORCEPROP 1 LAST LOCATION PL21
J 0
(-6250 5555);
DISPLAY 0.489362 (-6250 5555);
PAINT SKYBLUE (-6250 5555);
FORCEPROP 0 LAST $SEC 1
J 0
(-5950 5625);
DISPLAY 0.680851 (-5950 5625);
PAINT MONO (-5950 5625);
DISPLAY INVISIBLE (-5950 5625);
FORCEPROP 0 LAST CDS_SEC 1
J 0
(-5950 5625);
DISPLAY 1.021277 (-5950 5625);
DISPLAY INVISIBLE (-5950 5625);
FORCEPROP 0 LASTPIN (-6425 5425) $PN 1
J 2
(-6435 5435);
DISPLAY 0.489362 (-6435 5435);
PAINT MONO (-6435 5435);
FORCEPROP 0 LASTPIN (-6425 5175) $PN 2
J 2
(-6435 5185);
DISPLAY 0.489362 (-6435 5185);
PAINT MONO (-6435 5185);
FORCEPROP 0 LASTPIN (-5625 5175) $PN 3
J 0
(-5615 5185);
DISPLAY 0.489362 (-5615 5185);
PAINT MONO (-5615 5185);
FORCEPROP 0 LASTPIN (-5625 5425) $PN 4
J 0
(-5615 5435);
DISPLAY 0.489362 (-5615 5435);
PAINT MONO (-5615 5435);
FORCEPROP 1 LAST MATERIAL IND
J 0
(-6225 5475);
DISPLAY 0.489362 (-6225 5475);
PAINT SKYBLUE (-6225 5475);
FORCEPROP 2 LAST PART_TYPE SMLF
J 0
(-5950 5575);
DISPLAY 1.021277 (-5950 5575);
FORCEPROP 2 LAST VALUE 150NH
J 0
(-6125 5475);
DISPLAY 0.489362 (-6125 5475);
PAINT SKYBLUE (-6125 5475);
FORCEPROP 2 LAST CDS_LIB pure_quanta
J 0
(-6025 5300);
DISPLAY INVISIBLE (-6025 5300);
FORCEPROP 1 LAST NEEDS_NO_SIZE TRUE
J 0
(-6025 5300);
DISPLAY 0.468085 (-6025 5300);
PAINT GREEN (-6025 5300);
DISPLAY INVISIBLE (-6025 5300);
FORCEPROP 1 LAST PATH I61
J 0
(-5825 5455);
DISPLAY 0.723404 (-5825 5455);
PAINT GREEN (-5825 5455);
DISPLAY INVISIBLE (-5825 5455);
FORCEPROP 1 LAST PART_NUMBER CV+15^0TZ04
J 0
(-5975 5475);
DISPLAY 0.489362 (-5975 5475);
PAINT SKYBLUE (-5975 5475);
DISPLAY INVISIBLE (-5975 5475);
FORCEADD UNIVERSAL_GND..1
(-6850 6000);
FORCEPROP 3 LASTPIN (-6850 6050) SIG_NAME GND\g
J 0
(-6840 6060);
DISPLAY 0.659574 (-6840 6060);
PAINT MONO (-6840 6060);
DISPLAY INVISIBLE (-6840 6060);
FORCEPROP 2 LAST CDS_LIB pure_quanta_power
J 0
(-6850 6000);
PAINT MONO (-6850 6000);
DISPLAY INVISIBLE (-6850 6000);
FORCEPROP 1 LAST HDL_POWER GND
J 1
(-6825 5925);
DISPLAY 0.872340 (-6825 5925);
PAINT GREEN (-6825 5925);
DISPLAY INVISIBLE (-6825 5925);
FORCEPROP 1 LAST PATH I62
J 0
(-6775 6000);
DISPLAY 0.872340 (-6775 6000);
PAINT AQUA (-6775 6000);
DISPLAY INVISIBLE (-6775 6000);
FORCEADD Q_CAP..1
(-6850 6400);
FORCEPROP 1 LAST LOCATION PC187_3
J 0
(-6800 6500);
DISPLAY 0.489362 (-6800 6500);
PAINT SKYBLUE (-6800 6500);
FORCEPROP 0 LAST $SEC 1
J 0
(-6800 6550);
DISPLAY 0.680851 (-6800 6550);
PAINT MONO (-6800 6550);
DISPLAY INVISIBLE (-6800 6550);
FORCEPROP 0 LAST CDS_SEC 1
J 0
(-6800 6550);
DISPLAY 1.021277 (-6800 6550);
DISPLAY INVISIBLE (-6800 6550);
FORCEPROP 1 LASTPIN (-6850 6500) $PN 1
J 0
(-6840 6480);
DISPLAY 0.489362 (-6840 6480);
PAINT MONO (-6840 6480);
FORCEPROP 1 LASTPIN (-6850 6300) $PN 2
J 0
(-6840 6280);
DISPLAY 0.489362 (-6840 6280);
PAINT MONO (-6840 6280);
FORCEPROP 1 LAST VALUE 22UF
J 0
(-6800 6450);
DISPLAY 0.489362 (-6800 6450);
PAINT SKYBLUE (-6800 6450);
FORCEPROP 1 LAST MATERIAL X6S
J 0
(-6800 6300);
DISPLAY 0.489362 (-6800 6300);
PAINT SKYBLUE (-6800 6300);
FORCEPROP 1 LAST PACK_TYPE C0805
J 0
(-6800 6200);
DISPLAY 0.489362 (-6800 6200);
PAINT SKYBLUE (-6800 6200);
FORCEPROP 1 LAST TOLERANCE 20%
J 0
(-6800 6350);
DISPLAY 0.489362 (-6800 6350);
PAINT SKYBLUE (-6800 6350);
FORCEPROP 1 LAST VOLTAGE 16V
J 0
(-6800 6400);
DISPLAY 0.489362 (-6800 6400);
PAINT SKYBLUE (-6800 6400);
FORCEPROP 2 LAST CDS_LIB pure_quanta
J 0
(-6850 6400);
DISPLAY INVISIBLE (-6850 6400);
FORCEPROP 1 LAST PATH I63
J 0
(-6800 6550);
DISPLAY 0.978723 (-6800 6550);
PAINT WHITE (-6800 6550);
DISPLAY INVISIBLE (-6800 6550);
FORCEPROP 1 LAST PART_NUMBER CH6223MEA01
J 0
(-6800 6250);
DISPLAY 0.489362 (-6800 6250);
PAINT SKYBLUE (-6800 6250);
DISPLAY INVISIBLE (-6800 6250);
FORCEADD VCC_CORE..1
(-6850 6750);
FORCEPROP 3 LASTPIN (-6850 6700) SIG_NAME SW_P12V_AUX_PVDDIO_P0_FLT\g
J 0
(-6840 6710);
DISPLAY 0.659574 (-6840 6710);
PAINT MONO (-6840 6710);
DISPLAY INVISIBLE (-6840 6710);
FORCEPROP 1 LAST HDL_POWER SW_P12V_AUX_PVDDIO_P0_FLT
J 1
(-6850 6800);
DISPLAY 0.489362 (-6850 6800);
PAINT GREEN (-6850 6800);
FORCEPROP 2 LAST CDS_LIB pure_quanta_power
J 0
(-6850 6750);
DISPLAY INVISIBLE (-6850 6750);
FORCEPROP 1 LAST PATH I64
J 0
(-6800 6775);
DISPLAY 0.872340 (-6800 6775);
PAINT AQUA (-6800 6775);
DISPLAY INVISIBLE (-6800 6775);
FORCEADD OFFPAGE..3
(-5025 5175);
FORCEPROP 2 LAST $XR0 205 
J 0
(-4811 5175);
DISPLAY 0.638298 (-4811 5175);
PAINT MONO (-4811 5175);
FORCEPROP 2 LAST CDS_LIB standard
J 0
(-5025 5175);
DISPLAY INVISIBLE (-5025 5175);
FORCEPROP 1 LAST OFFPAGE TRUE
J 0
(-4700 5050);
DISPLAY 0.872340 (-4700 5050);
PAINT GREEN (-4700 5050);
DISPLAY INVISIBLE (-4700 5050);
FORCEPROP 1 LAST COMMENT_BODY TRUE
J 0
(-5075 5075);
DISPLAY 0.872340 (-5075 5075);
PAINT GREEN (-5075 5075);
DISPLAY INVISIBLE (-5075 5075);
FORCEPROP 2 LAST PATH I65
J 0
(-4800 5225);
DISPLAY 0.680851 (-4800 5225);
DISPLAY INVISIBLE (-4800 5225);
FORCEADD Q_CAP..1
(-4150 5225);
FORCEPROP 1 LAST LOCATION PC190_3
J 0
(-4100 5350);
DISPLAY 0.489362 (-4100 5350);
PAINT SKYBLUE (-4100 5350);
FORCEPROP 0 LAST $SEC 1
J 0
(-4100 5400);
DISPLAY 0.680851 (-4100 5400);
PAINT MONO (-4100 5400);
DISPLAY INVISIBLE (-4100 5400);
FORCEPROP 0 LAST CDS_SEC 1
J 0
(-4100 5400);
DISPLAY 1.021277 (-4100 5400);
DISPLAY INVISIBLE (-4100 5400);
FORCEPROP 1 LASTPIN (-4150 5325) $PN 1
J 0
(-4140 5305);
DISPLAY 0.489362 (-4140 5305);
PAINT MONO (-4140 5305);
FORCEPROP 1 LASTPIN (-4150 5125) $PN 2
J 0
(-4140 5105);
DISPLAY 0.489362 (-4140 5105);
PAINT MONO (-4140 5105);
FORCEPROP 1 LAST PACK_TYPE C0805
J 0
(-4100 5100);
DISPLAY 0.489362 (-4100 5100);
PAINT SKYBLUE (-4100 5100);
FORCEPROP 1 LAST MATERIAL X6S
J 0
(-4100 5150);
DISPLAY 0.489362 (-4100 5150);
PAINT SKYBLUE (-4100 5150);
FORCEPROP 1 LAST TOLERANCE 20%
J 0
(-4100 5200);
DISPLAY 0.489362 (-4100 5200);
PAINT SKYBLUE (-4100 5200);
FORCEPROP 1 LAST VALUE 22UF
J 0
(-4100 5300);
DISPLAY 0.489362 (-4100 5300);
PAINT SKYBLUE (-4100 5300);
FORCEPROP 1 LAST VOLTAGE 4V
J 0
(-4100 5250);
DISPLAY 0.489362 (-4100 5250);
PAINT SKYBLUE (-4100 5250);
FORCEPROP 2 LAST CDS_LIB pure_quanta
J 0
(-4150 5225);
DISPLAY INVISIBLE (-4150 5225);
FORCEPROP 1 LAST PATH I66
J 0
(-4100 5375);
DISPLAY 0.978723 (-4100 5375);
PAINT WHITE (-4100 5375);
DISPLAY INVISIBLE (-4100 5375);
FORCEPROP 1 LAST PART_NUMBER CH622KMEA03
J 0
(-4100 5050);
DISPLAY 0.489362 (-4100 5050);
PAINT SKYBLUE (-4100 5050);
DISPLAY INVISIBLE (-4100 5050);
FORCEADD UNIVERSAL_GND..1
(-3775 2075);
FORCEPROP 3 LASTPIN (-3775 2125) SIG_NAME GND\g
J 0
(-3765 2135);
DISPLAY 0.659574 (-3765 2135);
PAINT MONO (-3765 2135);
DISPLAY INVISIBLE (-3765 2135);
FORCEPROP 2 LAST CDS_LIB pure_quanta_power
J 0
(-3775 2075);
PAINT MONO (-3775 2075);
DISPLAY INVISIBLE (-3775 2075);
FORCEPROP 1 LAST HDL_POWER GND
J 1
(-3750 2000);
DISPLAY 0.872340 (-3750 2000);
PAINT GREEN (-3750 2000);
DISPLAY INVISIBLE (-3750 2000);
FORCEPROP 1 LAST PATH I67
J 0
(-3700 2075);
DISPLAY 0.872340 (-3700 2075);
PAINT AQUA (-3700 2075);
DISPLAY INVISIBLE (-3700 2075);
FORCEADD Q_CAP..1
(-3775 2425);
FORCEPROP 1 LAST LOCATION PC191_4
J 0
(-3725 2550);
DISPLAY 0.489362 (-3725 2550);
PAINT SKYBLUE (-3725 2550);
FORCEPROP 0 LAST $SEC 1
J 0
(-3725 2600);
DISPLAY 0.680851 (-3725 2600);
PAINT MONO (-3725 2600);
DISPLAY INVISIBLE (-3725 2600);
FORCEPROP 0 LAST CDS_SEC 1
J 0
(-3725 2600);
DISPLAY 1.021277 (-3725 2600);
DISPLAY INVISIBLE (-3725 2600);
FORCEPROP 1 LASTPIN (-3775 2525) $PN 1
J 0
(-3765 2505);
DISPLAY 0.489362 (-3765 2505);
PAINT MONO (-3765 2505);
FORCEPROP 1 LASTPIN (-3775 2325) $PN 2
J 0
(-3765 2305);
DISPLAY 0.489362 (-3765 2305);
PAINT MONO (-3765 2305);
FORCEPROP 1 LAST PACK_TYPE C0805
J 0
(-3725 2300);
DISPLAY 0.489362 (-3725 2300);
PAINT SKYBLUE (-3725 2300);
FORCEPROP 1 LAST MATERIAL X6S
J 0
(-3725 2350);
DISPLAY 0.489362 (-3725 2350);
PAINT SKYBLUE (-3725 2350);
FORCEPROP 1 LAST TOLERANCE 20%
J 0
(-3725 2400);
DISPLAY 0.489362 (-3725 2400);
PAINT SKYBLUE (-3725 2400);
FORCEPROP 1 LAST VALUE 22UF
J 0
(-3725 2500);
DISPLAY 0.489362 (-3725 2500);
PAINT SKYBLUE (-3725 2500);
FORCEPROP 1 LAST VOLTAGE 4V
J 0
(-3725 2450);
DISPLAY 0.489362 (-3725 2450);
PAINT SKYBLUE (-3725 2450);
FORCEPROP 2 LAST CDS_LIB pure_quanta
J 0
(-3775 2425);
DISPLAY INVISIBLE (-3775 2425);
FORCEPROP 1 LAST PATH I68
J 0
(-3725 2575);
DISPLAY 0.978723 (-3725 2575);
PAINT WHITE (-3725 2575);
DISPLAY INVISIBLE (-3725 2575);
FORCEPROP 1 LAST PART_NUMBER CH622KMEA03
J 0
(-3725 2250);
DISPLAY 0.489362 (-3725 2250);
PAINT SKYBLUE (-3725 2250);
DISPLAY INVISIBLE (-3725 2250);
FORCEADD VCC_CORE..1
(-3775 2750);
FORCEPROP 3 LASTPIN (-3775 2700) SIG_NAME PVDDIO_P0\g
J 0
(-3765 2710);
DISPLAY 0.659574 (-3765 2710);
PAINT MONO (-3765 2710);
DISPLAY INVISIBLE (-3765 2710);
FORCEPROP 1 LAST HDL_POWER PVDDIO_P0
J 1
(-3775 2800);
DISPLAY 0.489362 (-3775 2800);
PAINT GREEN (-3775 2800);
FORCEPROP 2 LAST CDS_LIB pure_quanta_power
J 0
(-3775 2750);
DISPLAY INVISIBLE (-3775 2750);
FORCEPROP 1 LAST PATH I69
J 0
(-3725 2775);
DISPLAY 0.872340 (-3725 2775);
PAINT AQUA (-3725 2775);
DISPLAY INVISIBLE (-3725 2775);
FORCEADD OFFPAGE..1
(-10900 2525);
FORCEPROP 2 LAST $XR5 206 
J 0
(-11782 2525);
DISPLAY 0.638298 (-11782 2525);
PAINT MONO (-11782 2525);
FORCEPROP 2 LAST $XR4 205 
J 0
(-11662 2525);
DISPLAY 0.638298 (-11662 2525);
PAINT MONO (-11662 2525);
FORCEPROP 2 LAST $XR3 203 
J 0
(-11542 2525);
DISPLAY 0.638298 (-11542 2525);
PAINT MONO (-11542 2525);
FORCEPROP 2 LAST $XR2 202 
J 0
(-11422 2525);
DISPLAY 0.638298 (-11422 2525);
PAINT MONO (-11422 2525);
FORCEPROP 2 LAST $XR1 201 
J 0
(-11302 2525);
DISPLAY 0.638298 (-11302 2525);
PAINT MONO (-11302 2525);
FORCEPROP 2 LAST $XR0 200 
J 0
(-11182 2525);
DISPLAY 0.638298 (-11182 2525);
PAINT MONO (-11182 2525);
FORCEPROP 2 LAST CDS_LIB standard
J 0
(-10900 2525);
DISPLAY INVISIBLE (-10900 2525);
FORCEPROP 1 LAST OFFPAGE TRUE
J 0
(-10575 2400);
DISPLAY 0.872340 (-10575 2400);
PAINT GREEN (-10575 2400);
DISPLAY INVISIBLE (-10575 2400);
FORCEPROP 1 LAST COMMENT_BODY TRUE
J 0
(-10775 2425);
DISPLAY 0.872340 (-10775 2425);
PAINT GREEN (-10775 2425);
DISPLAY INVISIBLE (-10775 2425);
FORCEPROP 2 LAST PATH I7
J 0
(-11150 2575);
DISPLAY 0.680851 (-11150 2575);
DISPLAY INVISIBLE (-11150 2575);
FORCEADD UNIVERSAL_GND..1
(-3725 4900);
FORCEPROP 3 LASTPIN (-3725 4950) SIG_NAME GND\g
J 0
(-3715 4960);
DISPLAY 0.659574 (-3715 4960);
PAINT MONO (-3715 4960);
DISPLAY INVISIBLE (-3715 4960);
FORCEPROP 2 LAST CDS_LIB pure_quanta_power
J 0
(-3725 4900);
PAINT MONO (-3725 4900);
DISPLAY INVISIBLE (-3725 4900);
FORCEPROP 1 LAST HDL_POWER GND
J 1
(-3700 4825);
DISPLAY 0.872340 (-3700 4825);
PAINT GREEN (-3700 4825);
DISPLAY INVISIBLE (-3700 4825);
FORCEPROP 1 LAST PATH I70
J 0
(-3650 4900);
DISPLAY 0.872340 (-3650 4900);
PAINT AQUA (-3650 4900);
DISPLAY INVISIBLE (-3650 4900);
FORCEADD Q_CAP..1
(-3725 5225);
FORCEPROP 1 LAST LOCATION PC192_3
J 0
(-3675 5350);
DISPLAY 0.489362 (-3675 5350);
PAINT SKYBLUE (-3675 5350);
FORCEPROP 0 LAST $SEC 1
J 0
(-3675 5400);
DISPLAY 0.680851 (-3675 5400);
PAINT MONO (-3675 5400);
DISPLAY INVISIBLE (-3675 5400);
FORCEPROP 0 LAST CDS_SEC 1
J 0
(-3675 5400);
DISPLAY 1.021277 (-3675 5400);
DISPLAY INVISIBLE (-3675 5400);
FORCEPROP 1 LASTPIN (-3725 5325) $PN 1
J 0
(-3715 5305);
DISPLAY 0.489362 (-3715 5305);
PAINT MONO (-3715 5305);
FORCEPROP 1 LASTPIN (-3725 5125) $PN 2
J 0
(-3715 5105);
DISPLAY 0.489362 (-3715 5105);
PAINT MONO (-3715 5105);
FORCEPROP 1 LAST PACK_TYPE C0805
J 0
(-3675 5100);
DISPLAY 0.489362 (-3675 5100);
PAINT SKYBLUE (-3675 5100);
FORCEPROP 1 LAST MATERIAL X6S
J 0
(-3675 5150);
DISPLAY 0.489362 (-3675 5150);
PAINT SKYBLUE (-3675 5150);
FORCEPROP 1 LAST TOLERANCE 20%
J 0
(-3675 5200);
DISPLAY 0.489362 (-3675 5200);
PAINT SKYBLUE (-3675 5200);
FORCEPROP 1 LAST VALUE 22UF
J 0
(-3675 5300);
DISPLAY 0.489362 (-3675 5300);
PAINT SKYBLUE (-3675 5300);
FORCEPROP 1 LAST VOLTAGE 4V
J 0
(-3675 5250);
DISPLAY 0.489362 (-3675 5250);
PAINT SKYBLUE (-3675 5250);
FORCEPROP 2 LAST CDS_LIB pure_quanta
J 0
(-3725 5225);
DISPLAY INVISIBLE (-3725 5225);
FORCEPROP 1 LAST PATH I71
J 0
(-3675 5375);
DISPLAY 0.978723 (-3675 5375);
PAINT WHITE (-3675 5375);
DISPLAY INVISIBLE (-3675 5375);
FORCEPROP 1 LAST PART_NUMBER CH622KMEA03
J 0
(-3675 5050);
DISPLAY 0.489362 (-3675 5050);
PAINT SKYBLUE (-3675 5050);
DISPLAY INVISIBLE (-3675 5050);
FORCEADD VCC_CORE..1
(-3725 5550);
FORCEPROP 3 LASTPIN (-3725 5500) SIG_NAME PVDDIO_P0\g
J 0
(-3715 5510);
DISPLAY 0.659574 (-3715 5510);
PAINT MONO (-3715 5510);
DISPLAY INVISIBLE (-3715 5510);
FORCEPROP 1 LAST HDL_POWER PVDDIO_P0
J 1
(-3725 5600);
DISPLAY 0.489362 (-3725 5600);
PAINT GREEN (-3725 5600);
FORCEPROP 2 LAST CDS_LIB pure_quanta_power
J 0
(-3725 5550);
DISPLAY INVISIBLE (-3725 5550);
FORCEPROP 1 LAST PATH I72
J 0
(-3675 5575);
DISPLAY 0.872340 (-3675 5575);
PAINT AQUA (-3675 5575);
DISPLAY INVISIBLE (-3675 5575);
FORCEADD ISL99390FRZTR5935..1
(-9350 2625);
FORCEPROP 1 LAST LOCATION PU20
J 0
(-9650 3500);
DISPLAY 0.489362 (-9650 3500);
PAINT SKYBLUE (-9650 3500);
FORCEPROP 0 LAST $SEC 1
J 0
(-9650 3675);
DISPLAY 0.680851 (-9650 3675);
PAINT MONO (-9650 3675);
DISPLAY INVISIBLE (-9650 3675);
FORCEPROP 2 LAST CDS_SEC 1
J 0
(-9600 3625);
DISPLAY 1.021277 (-9600 3625);
DISPLAY INVISIBLE (-9600 3625);
FORCEPROP 0 LASTPIN (-8950 2175) $PN 2
J 0
(-8940 2185);
DISPLAY 0.489362 (-8940 2185);
PAINT MONO (-8940 2185);
FORCEPROP 0 LASTPIN (-8950 2975) $PN 33
J 0
(-8940 2985);
DISPLAY 0.489362 (-8940 2985);
PAINT MONO (-8940 2985);
FORCEPROP 0 LASTPIN (-9800 2375) $PN 31
J 2
(-9810 2385);
DISPLAY 0.489362 (-9810 2385);
PAINT MONO (-9810 2385);
FORCEPROP 0 LASTPIN (-9800 2775) $PN 35
J 2
(-9810 2785);
DISPLAY 0.489362 (-9810 2785);
PAINT MONO (-9810 2785);
FORCEPROP 0 LASTPIN (-8950 2325) $PN 6
J 0
(-8940 2335);
DISPLAY 0.489362 (-8940 2335);
PAINT MONO (-8940 2335);
FORCEPROP 0 LASTPIN (-8950 2275) $PN 41
J 0
(-8940 2285);
DISPLAY 0.489362 (-8940 2285);
PAINT MONO (-8940 2285);
FORCEPROP 0 LASTPIN (-9800 2625) $PN 38
J 2
(-9810 2635);
DISPLAY 0.489362 (-9810 2635);
PAINT MONO (-9810 2635);
FORCEPROP 0 LASTPIN (-9800 2325) $PN 37
J 2
(-9810 2335);
DISPLAY 0.489362 (-9810 2335);
PAINT MONO (-9810 2335);
FORCEPROP 0 LASTPIN (-8950 2125) $PN 5
J 0
(-8940 2135);
DISPLAY 0.489362 (-8940 2135);
PAINT MONO (-8940 2135);
FORCEPROP 0 LASTPIN (-8950 2075) $PN 7_9-20_24
J 0
(-8940 2085);
DISPLAY 0.489362 (-8940 2085);
PAINT MONO (-8940 2085);
FORCEPROP 0 LASTPIN (-8950 2025) $PN 40
J 0
(-8940 2035);
DISPLAY 0.489362 (-8940 2035);
PAINT MONO (-8940 2035);
FORCEPROP 0 LASTPIN (-8950 2725) $PN 32
J 0
(-8940 2735);
DISPLAY 0.489362 (-8940 2735);
PAINT MONO (-8940 2735);
FORCEPROP 0 LASTPIN (-9800 3275) $PN 4
J 2
(-9810 3285);
DISPLAY 0.489362 (-9810 3285);
PAINT MONO (-9810 3285);
FORCEPROP 0 LASTPIN (-9800 2025) $PN 34
J 2
(-9810 2035);
DISPLAY 0.489362 (-9810 2035);
PAINT MONO (-9810 2035);
FORCEPROP 0 LASTPIN (-9800 2525) $PN 39
J 2
(-9810 2535);
DISPLAY 0.489362 (-9810 2535);
PAINT MONO (-9810 2535);
FORCEPROP 0 LASTPIN (-8950 2625) $PN 10_19
J 0
(-8940 2635);
DISPLAY 0.489362 (-8940 2635);
PAINT MONO (-8940 2635);
FORCEPROP 0 LASTPIN (-9800 2125) $PN 36
J 2
(-9810 2135);
DISPLAY 0.489362 (-9810 2135);
PAINT MONO (-9810 2135);
FORCEPROP 0 LASTPIN (-9800 2975) $PN 3
J 2
(-9810 2985);
DISPLAY 0.489362 (-9810 2985);
PAINT MONO (-9810 2985);
FORCEPROP 0 LASTPIN (-8950 3275) $PN 25_29
J 0
(-8940 3285);
DISPLAY 0.489362 (-8940 3285);
PAINT MONO (-8940 3285);
FORCEPROP 0 LASTPIN (-8950 3225) $PN 30
J 0
(-8940 3235);
DISPLAY 0.489362 (-8940 3235);
PAINT MONO (-8940 3235);
FORCEPROP 0 LASTPIN (-8950 2375) $PN 1
J 0
(-8940 2385);
DISPLAY 0.489362 (-8940 2385);
PAINT MONO (-8940 2385);
FORCEPROP 2 LAST VALUE ISL99390FRZ-TR5935
J 0
(-9650 3575);
DISPLAY 0.489362 (-9650 3575);
PAINT SKYBLUE (-9650 3575);
FORCEPROP 1 LAST MATERIAL IC
J 0
(-9650 3350);
DISPLAY 0.489362 (-9650 3350);
PAINT SKYBLUE (-9650 3350);
FORCEPROP 2 LAST PART_TYPE SMLF
J 0
(-9650 3625);
DISPLAY 0.638298 (-9650 3625);
FORCEPROP 1 LAST NEEDS_NO_SIZE TRUE
J 0
(-9350 2625);
DISPLAY 0.723404 (-9350 2625);
PAINT GREEN (-9350 2625);
DISPLAY INVISIBLE (-9350 2625);
FORCEPROP 1 LAST CDS_LMAN_SYM_OUTLINE -300,700,250,-650
J 0
(-9350 2625);
DISPLAY 0.468085 (-9350 2625);
PAINT GREEN (-9350 2625);
DISPLAY INVISIBLE (-9350 2625);
FORCEPROP 2 LAST CDS_LIB pure_quanta
J 0
(-9350 2625);
DISPLAY INVISIBLE (-9350 2625);
FORCEPROP 1 LAST PATH I73
J 0
(-9350 2625);
DISPLAY 0.723404 (-9350 2625);
PAINT GREEN (-9350 2625);
DISPLAY INVISIBLE (-9350 2625);
FORCEPROP 1 LAST PART_NUMBER AL099390004
J 0
(-9650 3425);
DISPLAY 0.489362 (-9650 3425);
PAINT SKYBLUE (-9650 3425);
DISPLAY INVISIBLE (-9650 3425);
FORCEADD OFFPAGE..5
(-10900 2625);
FORCEPROP 2 LAST $XR0 200 
J 0
(-11155 2625);
DISPLAY 0.638298 (-11155 2625);
PAINT MONO (-11155 2625);
FORCEPROP 2 LAST CDS_LIB standard
J 0
(-10900 2625);
DISPLAY INVISIBLE (-10900 2625);
FORCEPROP 1 LAST OFFPAGE TRUE
J 0
(-10575 2500);
DISPLAY 0.872340 (-10575 2500);
PAINT GREEN (-10575 2500);
DISPLAY INVISIBLE (-10575 2500);
FORCEPROP 1 LAST COMMENT_BODY TRUE
J 0
(-10800 2550);
DISPLAY 0.872340 (-10800 2550);
PAINT GREEN (-10800 2550);
DISPLAY INVISIBLE (-10800 2550);
FORCEPROP 2 LAST PATH I8
J 0
(-11175 2675);
DISPLAY 0.680851 (-11175 2675);
DISPLAY INVISIBLE (-11175 2675);
FORCEADD UNIVERSAL_GND..1
(-11050 2825);
FORCEPROP 3 LASTPIN (-11050 2875) SIG_NAME GND\g
J 0
(-11040 2885);
DISPLAY 0.659574 (-11040 2885);
PAINT MONO (-11040 2885);
DISPLAY INVISIBLE (-11040 2885);
FORCEPROP 2 LAST CDS_LIB pure_quanta_power
J 0
(-11050 2825);
DISPLAY INVISIBLE (-11050 2825);
FORCEPROP 1 LAST HDL_POWER GND
J 1
(-11025 2750);
DISPLAY 0.872340 (-11025 2750);
PAINT GREEN (-11025 2750);
DISPLAY INVISIBLE (-11025 2750);
FORCEPROP 1 LAST PATH I9
J 0
(-10975 2825);
DISPLAY 0.872340 (-10975 2825);
PAINT AQUA (-10975 2825);
DISPLAY INVISIBLE (-10975 2825);
FORCEADD QUANTA_TITLE_BLOCK_C..1
(-3075 825);
FORCEPROP 0 LAST CDS_CON_LAST_MODIFIED Thu Sep 14 16:12:19 2023
J 0
(-4960 840);
DISPLAY INVISIBLE (-4960 840);
FORCEPROP 1 LAST CUSTOM_TXT_CDS <CON_LAST_MODIFIED>
J 0
(-4960 840);
DISPLAY 0.978723 (-4960 840);
FORCEPROP 2 LAST CUSTOM_TXT_CDS <XR_PAGE_TITLE>
J 0
(-10965 6075);
DISPLAY 0.638298 (-10965 6075);
PAINT PINK (-10965 6075);
DISPLAY INVISIBLE (-10965 6075);
FORCEPROP 1 LAST CUSTOM_TXT_CDS <NAME_2>
J 0
(-6250 875);
FORCEPROP 1 LAST CUSTOM_TXT_CDS <NAME_1>
J 0
(-6250 1000);
FORCEPROP 1 LAST CUSTOM_TXT_CDS <Q_NUMBER>
J 0
(-4478 928);
DISPLAY 1.212766 (-4478 928);
FORCEPROP 1 LAST CUSTOM_TXT_CDS <Q_PROJ>
J 0
(-5457 927);
DISPLAY 1.212766 (-5457 927);
FORCEPROP 1 LAST CUSTOM_TXT_CDS <Q_REV>
J 0
(-3259 928);
DISPLAY 1.212766 (-3259 928);
FORCEPROP 1 LAST CUSTOM_TXT_CDS <CON_PAGE_NUM> OF <CON_TOTAL_PAGES>
J 0
(-3521 843);
DISPLAY 0.978723 (-3521 843);
FORCEPROP 1 LAST Q_TITLE PVDDIO_P0_VR PHASE 3&4
J 0
(-12375 875);
DISPLAY 2.446809 (-12375 875);
PAINT GREEN (-12375 875);
FORCEPROP 2 LAST PAGE_BORDER TRUE
J 0
(-10965 6075);
DISPLAY 0.638298 (-10965 6075);
PAINT PINK (-10965 6075);
DISPLAY INVISIBLE (-10965 6075);
FORCEPROP 1 LAST CDS_LMAN_SYM_OUTLINE -9475,6775,100,-125
J 0
(-3075 825);
DISPLAY 0.468085 (-3075 825);
PAINT GREEN (-3075 825);
DISPLAY INVISIBLE (-3075 825);
FORCEPROP 2 LAST CDS_LIB pure_quanta
J 0
(-3075 825);
DISPLAY INVISIBLE (-3075 825);
FORCEPROP 2 LAST CDS_XR_PAGE_TITLE CR-206 : @T6G_MB_LIB.T6G(SCH_1):PAGE206
J 0
(-10965 6075);
DISPLAY 0.638298 (-10965 6075);
PAINT PINK (-10965 6075);
DISPLAY INVISIBLE (-10965 6075);
FORCEPROP 1 LAST Q_DEPT BU9
J 1
(-6838 874);
DISPLAY 1.957447 (-6838 874);
PAINT GREEN (-6838 874);
DISPLAY INVISIBLE (-6838 874);
FORCEPROP 1 LAST COMMENT_BODY TRUE
J 0
(-3063 812);
DISPLAY 0.978723 (-3063 812);
PAINT GREEN (-3063 812);
DISPLAY INVISIBLE (-3063 812);
FORCEADD DNS..1
(-7975 5225);
PAINT RED (-7975 5225);
FORCEPROP 2 LAST CDS_LIB mstr_misc
J 0
(-7975 5225);
DISPLAY INVISIBLE (-7975 5225);
FORCEPROP 1 LAST COMMENT_BODY TRUE
R 1
J 0
(-7900 5000);
DISPLAY 0.872340 (-7900 5000);
PAINT GREEN (-7900 5000);
DISPLAY INVISIBLE (-7900 5000);
FORCEADD DNS..1
(-7975 4700);
PAINT RED (-7975 4700);
FORCEPROP 2 LAST CDS_LIB mstr_misc
J 0
(-7975 4700);
DISPLAY INVISIBLE (-7975 4700);
FORCEPROP 1 LAST COMMENT_BODY TRUE
R 1
J 0
(-7900 4475);
DISPLAY 0.872340 (-7900 4475);
PAINT GREEN (-7900 4475);
DISPLAY INVISIBLE (-7900 4475);
FORCEADD DNS..1
(-11350 4950);
PAINT RED (-11350 4950);
FORCEPROP 2 LAST CDS_LIB mstr_misc
J 0
(-11350 4950);
PAINT MONO (-11350 4950);
DISPLAY INVISIBLE (-11350 4950);
FORCEPROP 1 LAST COMMENT_BODY TRUE
R 1
J 0
(-11275 4725);
DISPLAY 0.872340 (-11275 4725);
PAINT GREEN (-11275 4725);
DISPLAY INVISIBLE (-11275 4725);
FORCEADD DNS..1
(-7975 2425);
PAINT RED (-7975 2425);
FORCEPROP 2 LAST CDS_LIB mstr_misc
J 0
(-7975 2425);
DISPLAY INVISIBLE (-7975 2425);
FORCEPROP 1 LAST COMMENT_BODY TRUE
R 1
J 0
(-7900 2200);
DISPLAY 0.872340 (-7900 2200);
PAINT GREEN (-7900 2200);
DISPLAY INVISIBLE (-7900 2200);
FORCEADD DNS..1
(-7975 1900);
PAINT RED (-7975 1900);
FORCEPROP 2 LAST CDS_LIB mstr_misc
J 0
(-7975 1900);
DISPLAY INVISIBLE (-7975 1900);
FORCEPROP 1 LAST COMMENT_BODY TRUE
R 1
J 0
(-7900 1675);
DISPLAY 0.872340 (-7900 1675);
PAINT GREEN (-7900 1675);
DISPLAY INVISIBLE (-7900 1675);
FORCEADD DNS..1
(-11375 2100);
PAINT RED (-11375 2100);
FORCEPROP 2 LAST CDS_LIB mstr_misc
J 0
(-11375 2100);
PAINT MONO (-11375 2100);
DISPLAY INVISIBLE (-11375 2100);
FORCEPROP 1 LAST COMMENT_BODY TRUE
R 1
J 0
(-11300 1875);
DISPLAY 0.872340 (-11300 1875);
PAINT GREEN (-11300 1875);
DISPLAY INVISIBLE (-11300 1875);
WIRE 16 -1 (-10700 3500)(-10700 3375);
WIRE 16 -1 (-11925 4900)(-11925 4950);
WIRE 16 -1 (-11900 2100)(-11900 2150);
WIRE 16 -1 (-11350 4875)(-11350 4800);
WIRE 16 -1 (-11025 5625)(-11025 5575);
WIRE 16 -1 (-10675 6200)(-10675 6075);
WIRE 16 -1 (-11375 2025)(-11375 1950);
WIRE 16 -1 (-7950 1800)(-7950 1725);
WIRE 16 -1 (-7400 2375)(-7525 2375);
WIRE 16 -1 (-7525 2375)(-7525 2325);
WIRE 16 -1 (-7950 4600)(-7950 4525);
WIRE 16 -1 (-11050 2925)(-11050 2875);
WIRE 16 -1 (-6725 3675)(-6725 3825);
WIRE 16 -1 (-6725 3900)(-6725 3825);
WIRE 16 -1 (-6725 3825)(-7200 3825);
WIRE 16 -1 (-7200 3675)(-7200 3825);
WIRE 16 -1 (-7600 3825)(-7200 3825);
WIRE 16 -1 (-7600 3825)(-7600 3675);
WIRE 16 -1 (-8000 3825)(-7600 3825);
WIRE 16 -1 (-8000 3675)(-8000 3825);
WIRE 16 -1 (-8475 3825)(-8000 3825);
WIRE 16 -1 (-8475 3700)(-8475 3825);
WIRE 16 -1 (-8775 3825)(-8475 3825);
WIRE 16 -1 (-8775 3825)(-8775 3275);
WIRE 16 -1 (-8775 3275)(-8775 3225);
WIRE 16 -1 (-8950 3275)(-8775 3275);
WIRE 16 -1 (-8775 3225)(-8950 3225);
WIRE 16 -1 (-6725 3475)(-6725 3325);
WIRE 16 -1 (-6725 3250)(-6725 3325);
WIRE 16 -1 (-6725 3325)(-7200 3325);
WIRE 16 -1 (-7200 3475)(-7200 3325);
WIRE 16 -1 (-7600 3325)(-7200 3325);
WIRE 16 -1 (-7600 3475)(-7600 3325);
WIRE 16 -1 (-7600 3325)(-8000 3325);
WIRE 16 -1 (-8000 3475)(-8000 3325);
WIRE 16 -1 (-8475 3325)(-8000 3325);
WIRE 16 -1 (-8475 3500)(-8475 3325);
WIRE 16 -1 (-8500 6275)(-8500 6125);
WIRE 16 -1 (-8500 6125)(-8075 6125);
WIRE 16 -1 (-8075 6275)(-8075 6125);
WIRE 16 -1 (-7675 6125)(-8075 6125);
WIRE 16 -1 (-7675 6275)(-7675 6125);
WIRE 16 -1 (-7675 6125)(-7275 6125);
WIRE 16 -1 (-7275 6275)(-7275 6125);
WIRE 16 -1 (-6850 6125)(-7275 6125);
WIRE 16 -1 (-6850 6300)(-6850 6125);
WIRE 16 -1 (-6850 6050)(-6850 6125);
WIRE 16 -1 (-9800 5575)(-9950 5575);
WIRE 16 -1 (-9950 5775)(-9950 5575);
WIRE 16 -1 (-9800 5775)(-9950 5775);
WIRE 16 -1 (-9950 5775)(-10375 5775);
FORCEPROP 0 LAST CDS_PHYS_NET_NAME PVDDIO_P0_VCC3
J 0
(-10310 5815);
PAINT MONO (-10310 5815);
DISPLAY INVISIBLE (-10310 5815);
FORCEPROP 2 LAST SIG_NAME PVDDIO_P0_VCC3
J 0
(-10335 5785);
DISPLAY 0.489362 (-10335 5785);
FORCEPROP 2 LASTPROP $XRERR UNIQUE?
J 0
(-10575 5785);
DISPLAY 0.638298 (-10575 5785);
PAINT MONO (-10575 5785);
DISPLAY INVISIBLE (-10575 5785);
WIRE 16 -1 (-10375 5775)(-10375 5900);
WIRE 16 -1 (-11025 5900)(-10375 5900);
WIRE 16 -1 (-11025 6175)(-11025 5900);
WIRE 16 -1 (-11025 5900)(-11025 5825);
WIRE 16 -1 (-8950 5775)(-8100 5775);
FORCEPROP 2 LAST SIG_NAME SW_PVDDIO_P0_BOOT3
J 0
(-8760 5810);
DISPLAY 0.489362 (-8760 5810);
FORCEPROP 2 LASTPROP $XRERR UNIQUE?
J 0
(-9000 5810);
DISPLAY 0.638298 (-9000 5810);
PAINT MONO (-9000 5810);
DISPLAY INVISIBLE (-9000 5810);
WIRE 16 -1 (-7050 5775)(-7050 5750);
WIRE 16 -1 (-7900 5775)(-7050 5775);
FORCEPROP 2 LAST SIG_NAME SW_PVDDIO_P0_BOOT3_R
J 0
(-7610 5785);
DISPLAY 0.489362 (-7610 5785);
FORCEPROP 2 LASTPROP $XRERR UNIQUE?
J 0
(-7850 5785);
DISPLAY 0.638298 (-7850 5785);
PAINT MONO (-7850 5785);
DISPLAY INVISIBLE (-7850 5785);
WIRE 16 -1 (-8950 2975)(-8325 2975);
FORCEPROP 2 LAST SIG_NAME SW_PVDDIO_P0_BOOT4
J 0
(-8735 2985);
DISPLAY 0.489362 (-8735 2985);
FORCEPROP 2 LASTPROP $XRERR UNIQUE?
J 0
(-8975 2985);
DISPLAY 0.638298 (-8975 2985);
PAINT MONO (-8975 2985);
DISPLAY INVISIBLE (-8975 2985);
WIRE 16 -1 (-7350 2975)(-7350 2950);
WIRE 16 -1 (-8125 2975)(-7350 2975);
FORCEPROP 2 LAST SIG_NAME SW_PVDDIO_P0_BOOT4_R
J 0
(-7835 2985);
DISPLAY 0.489362 (-7835 2985);
FORCEPROP 2 LASTPROP $XRERR UNIQUE?
J 0
(-8075 2985);
DISPLAY 0.638298 (-8075 2985);
PAINT MONO (-8075 2985);
DISPLAY INVISIBLE (-8075 2985);
WIRE 16 -1 (-9950 3275)(-9800 3275);
WIRE 16 -1 (-9950 3275)(-9950 3800);
WIRE 16 -1 (-10700 3800)(-9950 3800);
WIRE 16 -1 (-10700 3700)(-10700 3800);
WIRE 16 -1 (-10700 3800)(-11050 3800);
WIRE 16 -1 (-11050 3950)(-11050 3800);
WIRE 16 -1 (-11050 3675)(-11050 3800);
WIRE 16 -1 (-8700 2125)(-8700 2075);
WIRE 16 -1 (-8700 2125)(-8700 2175);
WIRE 16 -1 (-8950 2125)(-8700 2125);
WIRE 16 -1 (-8950 2075)(-8700 2075);
WIRE 16 -1 (-8700 2075)(-8700 2025);
WIRE 16 -1 (-8950 2025)(-8700 2025);
WIRE 16 -1 (-8700 2025)(-8700 1950);
WIRE 16 -1 (-8700 2175)(-8950 2175);
WIRE 16 -1 (-11025 6375)(-11025 6500);
WIRE 16 -1 (-10675 6500)(-11025 6500);
WIRE 16 -1 (-11025 6650)(-11025 6500);
WIRE 16 -1 (-10350 6500)(-10675 6500);
WIRE 16 -1 (-10675 6400)(-10675 6500);
WIRE 16 -1 (-10350 6075)(-10350 6500);
WIRE 16 -1 (-10350 6075)(-9800 6075);
WIRE 16 -1 (-8950 4875)(-8700 4875);
WIRE 16 -1 (-8700 4925)(-8700 4875);
WIRE 16 -1 (-8700 4875)(-8700 4825);
WIRE 16 -1 (-8950 4825)(-8700 4825);
WIRE 16 -1 (-8700 4825)(-8700 4750);
WIRE 16 -1 (-8700 4925)(-8700 4975);
WIRE 16 -1 (-8950 4925)(-8700 4925);
WIRE 16 -1 (-8700 4975)(-8950 4975);
WIRE 16 -1 (-3775 2325)(-3775 2200);
WIRE 16 -1 (-3775 2125)(-3775 2200);
WIRE 16 -1 (-3775 2200)(-4200 2200);
WIRE 16 -1 (-4200 2200)(-4200 2325);
WIRE 16 -1 (-3775 2525)(-3775 2625);
WIRE 16 -1 (-3775 2700)(-3775 2625);
WIRE 16 -1 (-4200 2625)(-3775 2625);
WIRE 16 -1 (-4200 2525)(-4200 2625);
WIRE 16 -1 (-4200 2625)(-4825 2625);
WIRE 16 -1 (-4825 2625)(-5875 2625);
WIRE 16 -1 (-4825 1500)(-4825 2625);
WIRE 16 -1 (-4825 1500)(-6700 1500);
WIRE 16 -1 (-3725 5125)(-3725 5000);
WIRE 16 -1 (-3725 4950)(-3725 5000);
WIRE 16 -1 (-3725 5000)(-4150 5000);
WIRE 16 -1 (-4150 5000)(-4150 5125);
WIRE 16 -1 (-4525 5425)(-4150 5425);
WIRE 16 -1 (-4525 5425)(-4525 4300);
WIRE 16 -1 (-4525 5425)(-5625 5425);
WIRE 16 -1 (-4150 5425)(-3725 5425);
WIRE 16 -1 (-4150 5425)(-4150 5325);
WIRE 16 -1 (-3725 5500)(-3725 5425);
WIRE 16 -1 (-3725 5325)(-3725 5425);
WIRE 16 -1 (-4525 4300)(-6600 4300);
WIRE 16 -1 (-10225 5175)(-9800 5175);
FORCEPROP 2 LAST SIG_NAME NC_PVDDIO_P0_DNC3
J 0
(-10245 5185);
DISPLAY 0.489362 (-10245 5185);
FORCEPROP 2 LASTPROP $XRERR UNIQUE?
J 0
(-10465 5175);
DISPLAY 0.638298 (-10465 5175);
PAINT MONO (-10465 5175);
DISPLAY INVISIBLE (-10465 5175);
WIRE 16 -1 (-9950 5325)(-9950 5250);
FORCEPROP 0 LAST CDS_PHYS_NET_NAME PVDDCR_CPU1_P0_VCCS
J 0
(-9950 5275);
PAINT MONO (-9950 5275);
DISPLAY INVISIBLE (-9950 5275);
WIRE 16 -1 (-9950 5325)(-9800 5325);
WIRE 16 -1 (-10825 5325)(-9950 5325);
FORCEPROP 2 LAST SIG_NAME PVDDCR_CPU1_P0_VCCS
J 0
(-10760 5335);
DISPLAY 0.489362 (-10760 5335);
WIRE 16 -1 (-9950 5250)(-11925 5250);
WIRE 16 -1 (-11925 5250)(-11925 5150);
WIRE 16 -1 (-11375 2325)(-9800 2325);
FORCEPROP 2 LAST SIG_NAME PVDDIO_P0_LSET4
J 0
(-10785 2335);
DISPLAY 0.489362 (-10785 2335);
FORCEPROP 2 LASTPROP $XRERR UNIQUE?
J 0
(-11025 2335);
DISPLAY 0.638298 (-11025 2335);
PAINT MONO (-11025 2335);
DISPLAY INVISIBLE (-11025 2335);
WIRE 16 -1 (-11375 2325)(-11375 2225);
WIRE 16 -1 (-9950 2525)(-9950 2450);
FORCEPROP 0 LAST CDS_PHYS_NET_NAME PVDDCR_CPU1_P0_VCCS
J 0
(-9950 2475);
PAINT MONO (-9950 2475);
DISPLAY INVISIBLE (-9950 2475);
WIRE 16 -1 (-9950 2525)(-9800 2525);
WIRE 16 -1 (-10850 2525)(-9950 2525);
FORCEPROP 2 LAST SIG_NAME PVDDCR_CPU1_P0_VCCS
J 0
(-10785 2535);
DISPLAY 0.489362 (-10785 2535);
WIRE 16 -1 (-9950 2450)(-11900 2450);
WIRE 16 -1 (-11900 2450)(-11900 2350);
WIRE 16 -1 (-9800 2125)(-10850 2125);
FORCEPROP 2 LAST SIG_NAME PVDDIO_P0_TEMP1
J 0
(-10785 2135);
DISPLAY 0.489362 (-10785 2135);
WIRE 16 -1 (-10225 2375)(-9800 2375);
FORCEPROP 2 LAST SIG_NAME NC_PVDDIO_P0_DNC4
J 0
(-10295 2385);
DISPLAY 0.489362 (-10295 2385);
FORCEPROP 2 LASTPROP $XRERR UNIQUE?
J 0
(-10465 2375);
DISPLAY 0.638298 (-10465 2375);
PAINT MONO (-10465 2375);
DISPLAY INVISIBLE (-10465 2375);
WIRE 16 -1 (-9800 2025)(-10850 2025);
FORCEPROP 2 LAST SIG_NAME PVDDIO_P0_PWM4
J 0
(-10785 2035);
DISPLAY 0.489362 (-10785 2035);
WIRE 16 -1 (-9800 2625)(-10850 2625);
FORCEPROP 2 LAST SIG_NAME PVDDIO_P0_IMON4
J 0
(-10785 2635);
DISPLAY 0.489362 (-10785 2635);
WIRE 16 -1 (-8950 2325)(-8450 2325);
FORCEPROP 2 LAST SIG_NAME NC_PVDDIO_P0_GL1_4
J 0
(-8835 2335);
DISPLAY 0.489362 (-8835 2335);
FORCEPROP 2 LASTPROP $XRERR UNIQUE?
J 0
(-8420 2325);
DISPLAY 0.638298 (-8420 2325);
PAINT MONO (-8420 2325);
DISPLAY INVISIBLE (-8420 2325);
WIRE 16 -1 (-8950 2275)(-8450 2275);
FORCEPROP 2 LAST SIG_NAME NC_PVDDIO_P0_GL2_4
J 0
(-8835 2285);
DISPLAY 0.489362 (-8835 2285);
FORCEPROP 2 LASTPROP $XRERR UNIQUE?
J 0
(-8420 2275);
DISPLAY 0.638298 (-8420 2275);
PAINT MONO (-8420 2275);
DISPLAY INVISIBLE (-8420 2275);
WIRE 16 -1 (-8950 2375)(-8225 2375);
FORCEPROP 2 LAST SIG_NAME PVDDIO_P0_VOS4
J 0
(-8835 2400);
DISPLAY 0.489362 (-8835 2400);
FORCEPROP 2 LASTPROP $XRERR UNIQUE?
J 0
(-9075 2400);
DISPLAY 0.638298 (-9075 2400);
PAINT MONO (-9075 2400);
DISPLAY INVISIBLE (-9075 2400);
WIRE 16 -1 (-8225 2375)(-8225 1500);
WIRE 16 -1 (-6900 1500)(-8225 1500);
WIRE 16 -1 (-9800 2775)(-9950 2775);
WIRE 16 -1 (-9950 2975)(-9950 2775);
WIRE 16 -1 (-9800 2975)(-9950 2975);
WIRE 16 -1 (-9950 2975)(-10475 2975);
FORCEPROP 0 LAST CDS_PHYS_NET_NAME PVDDIO_P0_VCC4
J 0
(-10360 3015);
PAINT MONO (-10360 3015);
DISPLAY INVISIBLE (-10360 3015);
FORCEPROP 2 LAST SIG_NAME PVDDIO_P0_VCC4
J 0
(-10385 2985);
DISPLAY 0.489362 (-10385 2985);
FORCEPROP 2 LASTPROP $XRERR UNIQUE?
J 0
(-10625 2985);
DISPLAY 0.638298 (-10625 2985);
PAINT MONO (-10625 2985);
DISPLAY INVISIBLE (-10625 2985);
WIRE 16 -1 (-10475 3200)(-10475 2975);
WIRE 16 -1 (-11050 3200)(-10475 3200);
WIRE 16 -1 (-11050 3475)(-11050 3200);
WIRE 16 -1 (-11050 3200)(-11050 3125);
WIRE 16 -1 (-11350 5125)(-9800 5125);
FORCEPROP 0 LAST CDS_PHYS_NET_NAME PVDDIO_P0_LSET3
J 0
(-10760 5165);
PAINT MONO (-10760 5165);
DISPLAY INVISIBLE (-10760 5165);
FORCEPROP 2 LAST SIG_NAME PVDDIO_P0_LSET3
J 0
(-10760 5135);
DISPLAY 0.489362 (-10760 5135);
FORCEPROP 2 LASTPROP $XRERR UNIQUE?
J 0
(-11000 5135);
DISPLAY 0.638298 (-11000 5135);
PAINT MONO (-11000 5135);
DISPLAY INVISIBLE (-11000 5135);
WIRE 16 -1 (-11350 5125)(-11350 5075);
WIRE 16 -1 (-9800 4825)(-10825 4825);
FORCEPROP 2 LAST SIG_NAME PVDDIO_P0_PWM3
J 0
(-10760 4835);
DISPLAY 0.489362 (-10760 4835);
WIRE 16 -1 (-9800 4925)(-10825 4925);
FORCEPROP 2 LAST SIG_NAME PVDDIO_P0_TEMP1
J 0
(-10760 4935);
DISPLAY 0.489362 (-10760 4935);
WIRE 16 -1 (-9800 5425)(-10825 5425);
FORCEPROP 2 LAST SIG_NAME PVDDIO_P0_IMON3
J 0
(-10760 5435);
DISPLAY 0.489362 (-10760 5435);
WIRE 16 -1 (-8500 5075)(-8950 5075);
FORCEPROP 2 LAST SIG_NAME NC_PVDDIO_P0_GL2_3
J 0
(-8860 5085);
DISPLAY 0.489362 (-8860 5085);
FORCEPROP 2 LASTPROP $XRERR UNIQUE?
J 0
(-8470 5075);
DISPLAY 0.638298 (-8470 5075);
PAINT MONO (-8470 5075);
DISPLAY INVISIBLE (-8470 5075);
WIRE 16 -1 (-8500 5125)(-8950 5125);
FORCEPROP 2 LAST SIG_NAME NC_PVDDIO_P0_GL1_3
J 0
(-8860 5135);
DISPLAY 0.489362 (-8860 5135);
FORCEPROP 2 LASTPROP $XRERR UNIQUE?
J 0
(-8470 5125);
DISPLAY 0.638298 (-8470 5125);
PAINT MONO (-8470 5125);
DISPLAY INVISIBLE (-8470 5125);
WIRE 16 -1 (-7950 2325)(-7950 2000);
FORCEPROP 2 LAST SIG_NAME SW_PVDDIO_P0_SW4_RC
J 0
(-7910 2125);
DISPLAY 0.489362 (-7910 2125);
FORCEPROP 2 LASTPROP $XRERR UNIQUE?
J 0
(-8150 2125);
DISPLAY 0.638298 (-8150 2125);
PAINT MONO (-8150 2125);
DISPLAY INVISIBLE (-8150 2125);
WIRE 16 -1 (-7200 2375)(-6675 2375);
FORCEPROP 2 LAST SIG_NAME IND_PVDDIO_P0_CPL0
J 0
(-7135 2400);
DISPLAY 0.489362 (-7135 2400);
FORCEPROP 2 LASTPROP $XRERR UNIQUE?
J 0
(-7375 2400);
DISPLAY 0.638298 (-7375 2400);
PAINT MONO (-7375 2400);
DISPLAY INVISIBLE (-7375 2400);
WIRE 16 -1 (-5875 2375)(-5325 2375);
FORCEPROP 2 LAST SIG_NAME IND_PVDDIO_P0_CPL4
J 0
(-5835 2385);
DISPLAY 0.489362 (-5835 2385);
WIRE 16 -1 (-7950 5125)(-7950 4800);
FORCEPROP 2 LAST SIG_NAME SW_PVDDIO_P0_SW3_RC
J 0
(-7910 4935);
DISPLAY 0.489362 (-7910 4935);
FORCEPROP 2 LASTPROP $XRERR UNIQUE?
J 0
(-8150 4935);
DISPLAY 0.638298 (-8150 4935);
PAINT MONO (-8150 4935);
DISPLAY INVISIBLE (-8150 4935);
WIRE 16 -1 (-6425 5175)(-7100 5175);
FORCEPROP 2 LAST SIG_NAME IND_PVDDIO_P0_CPL4
J 0
(-6960 5185);
DISPLAY 0.489362 (-6960 5185);
WIRE 16 -1 (-5625 5175)(-5075 5175);
FORCEPROP 2 LAST SIG_NAME IND_PVDDIO_P0_CPL3
J 0
(-5510 5185);
DISPLAY 0.489362 (-5510 5185);
WIRE 16 -1 (-8950 2625)(-7950 2625);
FORCEPROP 2 LAST SIG_NAME SW_PVDDIO_P0_SW4
J 0
(-8760 2635);
DISPLAY 0.489362 (-8760 2635);
FORCEPROP 2 LASTPROP $XRERR UNIQUE?
J 0
(-9000 2635);
DISPLAY 0.638298 (-9000 2635);
PAINT MONO (-9000 2635);
DISPLAY INVISIBLE (-9000 2635);
WIRE 16 -1 (-7950 2625)(-6675 2625);
WIRE 16 -1 (-7950 2525)(-7950 2625);
WIRE 16 -1 (-8950 2725)(-7350 2725);
FORCEPROP 2 LAST SIG_NAME SW_PVDDIO_P0_BOOTR4
J 0
(-8760 2735);
DISPLAY 0.489362 (-8760 2735);
FORCEPROP 2 LASTPROP $XRERR UNIQUE?
J 0
(-9000 2735);
DISPLAY 0.638298 (-9000 2735);
PAINT MONO (-9000 2735);
DISPLAY INVISIBLE (-9000 2735);
WIRE 16 -1 (-7350 2725)(-7350 2750);
WIRE 16 -1 (-8950 5525)(-7050 5525);
FORCEPROP 2 LAST SIG_NAME SW_PVDDIO_P0_BOOTR3
J 0
(-8760 5535);
DISPLAY 0.489362 (-8760 5535);
FORCEPROP 2 LASTPROP $XRERR UNIQUE?
J 0
(-9000 5535);
DISPLAY 0.638298 (-9000 5535);
PAINT MONO (-9000 5535);
DISPLAY INVISIBLE (-9000 5535);
WIRE 16 -1 (-7050 5525)(-7050 5550);
WIRE 16 -1 (-8950 5175)(-8225 5175);
FORCEPROP 2 LAST SIG_NAME PVDDIO_P0_VOS3
J 0
(-8860 5200);
DISPLAY 0.489362 (-8860 5200);
FORCEPROP 2 LASTPROP $XRERR UNIQUE?
J 0
(-9100 5200);
DISPLAY 0.638298 (-9100 5200);
PAINT MONO (-9100 5200);
DISPLAY INVISIBLE (-9100 5200);
WIRE 16 -1 (-8225 5175)(-8225 4300);
WIRE 16 -1 (-6800 4300)(-8225 4300);
WIRE 16 -1 (-8950 5425)(-7950 5425);
FORCEPROP 2 LAST SIG_NAME SW_PVDDIO_P0_SW3
J 0
(-8760 5435);
DISPLAY 0.489362 (-8760 5435);
FORCEPROP 2 LASTPROP $XRERR UNIQUE?
J 0
(-9000 5435);
DISPLAY 0.638298 (-9000 5435);
PAINT MONO (-9000 5435);
DISPLAY INVISIBLE (-9000 5435);
WIRE 16 -1 (-7950 5425)(-6425 5425);
WIRE 16 -1 (-7950 5325)(-7950 5425);
WIRE 16 -1 (-6850 6700)(-6850 6625);
WIRE 16 -1 (-6850 6625)(-6850 6500);
WIRE 16 -1 (-6850 6625)(-7275 6625);
WIRE 16 -1 (-7275 6475)(-7275 6625);
WIRE 16 -1 (-7675 6625)(-7275 6625);
WIRE 16 -1 (-7675 6625)(-7675 6475);
WIRE 16 -1 (-8075 6625)(-7675 6625);
WIRE 16 -1 (-8075 6475)(-8075 6625);
WIRE 16 -1 (-8500 6625)(-8075 6625);
WIRE 16 -1 (-8500 6475)(-8500 6625);
WIRE 16 -1 (-8775 6625)(-8500 6625);
WIRE 16 -1 (-8775 6625)(-8775 6075);
WIRE 16 -1 (-8775 6075)(-8775 6025);
WIRE 16 -1 (-8950 6075)(-8775 6075);
WIRE 16 -1 (-8775 6025)(-8950 6025);
DOT 1 (-8075 6125);
DOT 1 (-11050 3200);
DOT 1 (-11050 3800);
DOT 1 (-10700 3800);
DOT 1 (-8700 2025);
DOT 1 (-8700 2075);
DOT 1 (-8700 2125);
DOT 1 (-9950 2525);
DOT 1 (-9950 2975);
DOT 1 (-8775 3275);
DOT 1 (-8475 3825);
DOT 1 (-11025 5900);
DOT 1 (-11025 6500);
DOT 1 (-10675 6500);
DOT 1 (-9950 5325);
DOT 1 (-9950 5775);
DOT 1 (-8700 4825);
DOT 1 (-8700 4875);
DOT 1 (-8700 4925);
DOT 1 (-8775 6075);
DOT 1 (-8500 6625);
DOT 1 (-8075 6625);
DOT 1 (-7950 2625);
DOT 1 (-8000 3325);
DOT 1 (-7600 3325);
DOT 1 (-7200 3325);
DOT 1 (-8000 3825);
DOT 1 (-7600 3825);
DOT 1 (-7200 3825);
DOT 1 (-6725 3325);
DOT 1 (-6725 3825);
DOT 1 (-4825 2625);
DOT 1 (-4200 2625);
DOT 1 (-7950 5425);
DOT 1 (-7275 6125);
DOT 1 (-6850 6125);
DOT 1 (-7675 6625);
DOT 1 (-7275 6625);
DOT 1 (-6850 6625);
DOT 1 (-4525 5425);
DOT 1 (-4150 5425);
DOT 1 (-3775 2200);
DOT 1 (-3775 2625);
DOT 1 (-3725 5000);
DOT 1 (-3725 5425);
DOT 1 (-7675 6125);
FORCENOTE
PVDDIO_P0_PHASE3
(-9650 6550) 0;
DISPLAY LEFT (-9650 6550);
DISPLAY 1.021277 (-9650 6550);
PAINT WHITE (-9650 6550);
FORCENOTE
ISAT:70A@100C
(-5850 2900) 0;
DISPLAY LEFT (-5850 2900);
DISPLAY 0.638298 (-5850 2900);
PAINT WHITE (-5850 2900);
FORCENOTE
11.0*7.5*12.5
(-5850 2850) 0;
DISPLAY LEFT (-5850 2850);
DISPLAY 0.638298 (-5850 2850);
PAINT WHITE (-5850 2850);
FORCENOTE
PGL6303.151HLT
(-5850 2950) 0;
DISPLAY LEFT (-5850 2950);
DISPLAY 0.638298 (-5850 2950);
PAINT WHITE (-5850 2950);
FORCENOTE
DCR=1-4,0.105M OHM
(-5850 2800) 0;
DISPLAY LEFT (-5850 2800);
DISPLAY 0.638298 (-5850 2800);
PAINT WHITE (-5850 2800);
FORCENOTE
DCR=2-3,0.27M OHM
(-5850 2750) 0;
DISPLAY LEFT (-5850 2750);
DISPLAY 0.638298 (-5850 2750);
PAINT WHITE (-5850 2750);
FORCENOTE
2ND=CV+15^0TZ01
(-5850 2700) 0;
DISPLAY LEFT (-5850 2700);
DISPLAY 0.638298 (-5850 2700);
PAINT WHITE (-5850 2700);
FORCENOTE
ISAT:70A@100C
(-5600 5675) 0;
DISPLAY LEFT (-5600 5675);
DISPLAY 0.638298 (-5600 5675);
PAINT WHITE (-5600 5675);
FORCENOTE
DCR=1-4,0.105M OHM
(-5600 5575) 0;
DISPLAY LEFT (-5600 5575);
DISPLAY 0.638298 (-5600 5575);
PAINT WHITE (-5600 5575);
FORCENOTE
11.0*7.5*12.5
(-5600 5625) 0;
DISPLAY LEFT (-5600 5625);
DISPLAY 0.638298 (-5600 5625);
PAINT WHITE (-5600 5625);
FORCENOTE
PGL6303.151HLT
(-5600 5725) 0;
DISPLAY LEFT (-5600 5725);
DISPLAY 0.638298 (-5600 5725);
PAINT WHITE (-5600 5725);
FORCENOTE
2ND=CV+15^0TZ01
(-5600 5475) 0;
DISPLAY LEFT (-5600 5475);
DISPLAY 0.638298 (-5600 5475);
PAINT WHITE (-5600 5475);
FORCENOTE
DCR=2-3,0.27M OHM
(-5600 5525) 0;
DISPLAY LEFT (-5600 5525);
DISPLAY 0.638298 (-5600 5525);
PAINT WHITE (-5600 5525);
FORCENOTE
2ND=CV+22Y0EZ01
(-7425 2100) 0;
DISPLAY LEFT (-7425 2100);
DISPLAY 0.638298 (-7425 2100);
PAINT WHITE (-7425 2100);
FORCENOTE
DCR=0.17M OHM
(-7425 2150) 0;
DISPLAY LEFT (-7425 2150);
DISPLAY 0.638298 (-7425 2150);
PAINT WHITE (-7425 2150);
FORCENOTE
6.5*6.5*10.0
(-7425 2200) 0;
DISPLAY LEFT (-7425 2200);
DISPLAY 0.638298 (-7425 2200);
PAINT WHITE (-7425 2200);
FORCENOTE
ISAT:30A@100C
(-7425 2250) 0;
DISPLAY LEFT (-7425 2250);
DISPLAY 0.638298 (-7425 2250);
PAINT WHITE (-7425 2250);
FORCENOTE
HCME656510Q-221QL
(-7425 2300) 0;
DISPLAY LEFT (-7425 2300);
DISPLAY 0.638298 (-7425 2300);
PAINT WHITE (-7425 2300);
FORCENOTE
PVDDIO_P0_PHASE4
(-9650 3700) 0;
DISPLAY LEFT (-9650 3700);
DISPLAY 1.021277 (-9650 3700);
PAINT WHITE (-9650 3700);
QUIT
